(kicad_sch
	(version 20250114)
	(generator "eeschema")
	(generator_version "9.0")
	(paper "A3")
	(title_block
		(title "Thunderbolt to 10GbE adapter")
		(date "2026-04-23")
		(rev "1.1.0")
		(company "Antmicro Ltd")
		(comment 1 "www.antmicro.com")
	)
	(bus_alias "CLK"
		(members "+" "-")
	)
	(bus_alias "JTAG"
		(members "~{JRST}" "JTCK" "JTMS" "JTDI" "JTDO")
	)
	(bus_alias "PCIe"
		(members "TX3+" "TX3-" "TX2+" "TX2-" "TX1+" "TX1-" "TX0+" "TX0-" "RX3+"
			"RX3-" "RX2+" "RX2-" "RX1+" "RX1-" "RX0+" "RX0-"
		)
	)
	(text "X710-AT2 PCIe Interface"
		(exclude_from_sim no)
		(at 215.9 50.8 0)
		(effects
			(font
				(size 2.54 2.54)
				(thickness 0.508)
				(bold yes)
			)
		)
	)
	(text_box "NOTE: Place this resistor close to the controller;\nthe trace length should be less than 25.4 mm."
		(exclude_from_sim no)
		(at 231.14 223.52 0)
		(size 50.8 6.35)
		(margins 0.9525 0.9525 0.9525 0.9525)
		(stroke
			(width 0)
			(type solid)
		)
		(fill
			(type none)
		)
		(effects
			(font
				(size 1.27 1.27)
			)
		)
	)
	(text_box "JTAG Debug Connector"
		(exclude_from_sim no)
		(at 254 129.54 0)
		(size 73.66 29.21)
		(margins 0.9525 0.9525 0.9525 0.9525)
		(stroke
			(width 0)
			(type solid)
		)
		(fill
			(type none)
		)
		(effects
			(font
				(size 1.27 1.27)
			)
			(justify left top)
		)
	)
	(junction
		(at 245.11 95.25)
		(diameter 0)
		(color 0 0 0 0)
	)
	(junction
		(at 262.89 90.17)
		(diameter 0)
		(color 0 0 0 0)
	)
	(junction
		(at 254 74.93)
		(diameter 0)
		(color 0 0 0 0)
	)
	(junction
		(at 254 92.71)
		(diameter 0)
		(color 0 0 0 0)
	)
	(junction
		(at 236.22 97.79)
		(diameter 0)
		(color 0 0 0 0)
	)
	(junction
		(at 245.11 74.93)
		(diameter 0)
		(color 0 0 0 0)
	)
	(junction
		(at 271.78 149.86)
		(diameter 0)
		(color 0 0 0 0)
	)
	(junction
		(at 271.78 87.63)
		(diameter 0)
		(color 0 0 0 0)
	)
	(no_connect
		(at 198.12 166.37)
	)
	(no_connect
		(at 198.12 181.61)
	)
	(no_connect
		(at 198.12 212.09)
	)
	(no_connect
		(at 198.12 204.47)
	)
	(no_connect
		(at 198.12 163.83)
	)
	(no_connect
		(at 198.12 219.71)
	)
	(no_connect
		(at 274.32 139.7)
	)
	(no_connect
		(at 198.12 194.31)
	)
	(no_connect
		(at 198.12 171.45)
	)
	(no_connect
		(at 198.12 217.17)
	)
	(no_connect
		(at 198.12 186.69)
	)
	(no_connect
		(at 198.12 179.07)
	)
	(no_connect
		(at 198.12 189.23)
	)
	(no_connect
		(at 198.12 196.85)
	)
	(no_connect
		(at 198.12 173.99)
	)
	(no_connect
		(at 198.12 201.93)
	)
	(no_connect
		(at 198.12 209.55)
	)
	(bus_entry
		(at 140.97 138.43)
		(size 2.54 -2.54)
		(stroke
			(width 0)
			(type default)
		)
	)
	(bus_entry
		(at 140.97 146.05)
		(size 2.54 -2.54)
		(stroke
			(width 0)
			(type default)
		)
	)
	(bus_entry
		(at 140.97 161.29)
		(size 2.54 -2.54)
		(stroke
			(width 0)
			(type default)
		)
	)
	(bus_entry
		(at 140.97 120.65)
		(size 2.54 -2.54)
		(stroke
			(width 0)
			(type default)
		)
	)
	(bus_entry
		(at 140.97 153.67)
		(size 2.54 -2.54)
		(stroke
			(width 0)
			(type default)
		)
	)
	(bus_entry
		(at 140.97 107.95)
		(size 2.54 -2.54)
		(stroke
			(width 0)
			(type default)
		)
	)
	(bus_entry
		(at 140.97 143.51)
		(size 2.54 -2.54)
		(stroke
			(width 0)
			(type default)
		)
	)
	(bus_entry
		(at 140.97 113.03)
		(size 2.54 -2.54)
		(stroke
			(width 0)
			(type default)
		)
	)
	(bus_entry
		(at 140.97 115.57)
		(size 2.54 -2.54)
		(stroke
			(width 0)
			(type default)
		)
	)
	(bus_entry
		(at 140.97 158.75)
		(size 2.54 -2.54)
		(stroke
			(width 0)
			(type default)
		)
	)
	(bus_entry
		(at 140.97 135.89)
		(size 2.54 -2.54)
		(stroke
			(width 0)
			(type default)
		)
	)
	(bus_entry
		(at 140.97 151.13)
		(size 2.54 -2.54)
		(stroke
			(width 0)
			(type default)
		)
	)
	(bus_entry
		(at 140.97 97.79)
		(size 2.54 -2.54)
		(stroke
			(width 0)
			(type default)
		)
	)
	(bus_entry
		(at 140.97 130.81)
		(size 2.54 -2.54)
		(stroke
			(width 0)
			(type default)
		)
	)
	(bus_entry
		(at 140.97 105.41)
		(size 2.54 -2.54)
		(stroke
			(width 0)
			(type default)
		)
	)
	(bus_entry
		(at 140.97 100.33)
		(size 2.54 -2.54)
		(stroke
			(width 0)
			(type default)
		)
	)
	(bus_entry
		(at 140.97 123.19)
		(size 2.54 -2.54)
		(stroke
			(width 0)
			(type default)
		)
	)
	(bus_entry
		(at 140.97 128.27)
		(size 2.54 -2.54)
		(stroke
			(width 0)
			(type default)
		)
	)
	(bus
		(pts
			(xy 140.97 130.81) (xy 140.97 135.89)
		)
		(stroke
			(width 0)
			(type default)
		)
	)
	(bus
		(pts
			(xy 140.97 128.27) (xy 140.97 130.81)
		)
		(stroke
			(width 0)
			(type default)
		)
	)
	(wire
		(pts
			(xy 233.68 92.71) (xy 254 92.71)
		)
		(stroke
			(width 0)
			(type default)
		)
	)
	(wire
		(pts
			(xy 143.51 143.51) (xy 198.12 143.51)
		)
		(stroke
			(width 0)
			(type default)
		)
	)
	(bus
		(pts
			(xy 140.97 135.89) (xy 140.97 138.43)
		)
		(stroke
			(width 0)
			(type default)
		)
	)
	(bus
		(pts
			(xy 140.97 143.51) (xy 140.97 146.05)
		)
		(stroke
			(width 0)
			(type default)
		)
	)
	(wire
		(pts
			(xy 143.51 151.13) (xy 160.02 151.13)
		)
		(stroke
			(width 0)
			(type default)
		)
	)
	(bus
		(pts
			(xy 140.97 138.43) (xy 140.97 143.51)
		)
		(stroke
			(width 0)
			(type default)
		)
	)
	(wire
		(pts
			(xy 236.22 77.47) (xy 236.22 74.93)
		)
		(stroke
			(width 0)
			(type default)
		)
	)
	(wire
		(pts
			(xy 271.78 106.68) (xy 271.78 109.22)
		)
		(stroke
			(width 0)
			(type default)
		)
	)
	(wire
		(pts
			(xy 143.51 128.27) (xy 198.12 128.27)
		)
		(stroke
			(width 0)
			(type default)
		)
	)
	(wire
		(pts
			(xy 254 72.39) (xy 254 74.93)
		)
		(stroke
			(width 0)
			(type default)
		)
	)
	(wire
		(pts
			(xy 156.21 87.63) (xy 198.12 87.63)
		)
		(stroke
			(width 0)
			(type default)
		)
	)
	(bus
		(pts
			(xy 140.97 151.13) (xy 140.97 153.67)
		)
		(stroke
			(width 0)
			(type default)
		)
	)
	(wire
		(pts
			(xy 236.22 82.55) (xy 236.22 97.79)
		)
		(stroke
			(width 0)
			(type default)
		)
	)
	(wire
		(pts
			(xy 233.68 97.79) (xy 236.22 97.79)
		)
		(stroke
			(width 0)
			(type default)
		)
	)
	(wire
		(pts
			(xy 262.89 90.17) (xy 290.83 90.17)
		)
		(stroke
			(width 0)
			(type default)
		)
	)
	(wire
		(pts
			(xy 274.32 149.86) (xy 271.78 149.86)
		)
		(stroke
			(width 0)
			(type default)
		)
	)
	(bus
		(pts
			(xy 140.97 120.65) (xy 140.97 123.19)
		)
		(stroke
			(width 0)
			(type default)
		)
	)
	(wire
		(pts
			(xy 254 92.71) (xy 290.83 92.71)
		)
		(stroke
			(width 0)
			(type default)
		)
	)
	(wire
		(pts
			(xy 325.12 144.78) (xy 306.07 144.78)
		)
		(stroke
			(width 0)
			(type default)
		)
	)
	(wire
		(pts
			(xy 255.27 142.24) (xy 274.32 142.24)
		)
		(stroke
			(width 0)
			(type default)
		)
	)
	(wire
		(pts
			(xy 165.1 135.89) (xy 198.12 135.89)
		)
		(stroke
			(width 0)
			(type default)
		)
	)
	(wire
		(pts
			(xy 325.12 149.86) (xy 306.07 149.86)
		)
		(stroke
			(width 0)
			(type default)
		)
	)
	(wire
		(pts
			(xy 143.51 125.73) (xy 198.12 125.73)
		)
		(stroke
			(width 0)
			(type default)
		)
	)
	(bus
		(pts
			(xy 140.97 97.79) (xy 140.97 100.33)
		)
		(stroke
			(width 0)
			(type default)
		)
	)
	(wire
		(pts
			(xy 271.78 149.86) (xy 271.78 152.4)
		)
		(stroke
			(width 0)
			(type default)
		)
	)
	(wire
		(pts
			(xy 236.22 97.79) (xy 290.83 97.79)
		)
		(stroke
			(width 0)
			(type default)
		)
	)
	(wire
		(pts
			(xy 255.27 147.32) (xy 274.32 147.32)
		)
		(stroke
			(width 0)
			(type default)
		)
	)
	(wire
		(pts
			(xy 233.68 217.17) (xy 243.84 217.17)
		)
		(stroke
			(width 0)
			(type default)
		)
	)
	(wire
		(pts
			(xy 143.51 102.87) (xy 168.91 102.87)
		)
		(stroke
			(width 0)
			(type default)
		)
	)
	(bus
		(pts
			(xy 140.97 100.33) (xy 140.97 102.87)
		)
		(stroke
			(width 0)
			(type default)
		)
	)
	(wire
		(pts
			(xy 262.89 106.68) (xy 262.89 109.22)
		)
		(stroke
			(width 0)
			(type default)
		)
	)
	(wire
		(pts
			(xy 274.32 144.78) (xy 271.78 144.78)
		)
		(stroke
			(width 0)
			(type default)
		)
	)
	(wire
		(pts
			(xy 173.99 118.11) (xy 198.12 118.11)
		)
		(stroke
			(width 0)
			(type default)
		)
	)
	(wire
		(pts
			(xy 308.61 142.24) (xy 306.07 142.24)
		)
		(stroke
			(width 0)
			(type default)
		)
	)
	(bus
		(pts
			(xy 140.97 158.75) (xy 140.97 161.29)
		)
		(stroke
			(width 0)
			(type default)
		)
	)
	(wire
		(pts
			(xy 143.51 97.79) (xy 162.56 97.79)
		)
		(stroke
			(width 0)
			(type default)
		)
	)
	(wire
		(pts
			(xy 143.51 105.41) (xy 160.02 105.41)
		)
		(stroke
			(width 0)
			(type default)
		)
	)
	(wire
		(pts
			(xy 251.46 217.17) (xy 251.46 219.71)
		)
		(stroke
			(width 0)
			(type default)
		)
	)
	(wire
		(pts
			(xy 143.51 95.25) (xy 162.56 95.25)
		)
		(stroke
			(width 0)
			(type default)
		)
	)
	(wire
		(pts
			(xy 233.68 87.63) (xy 271.78 87.63)
		)
		(stroke
			(width 0)
			(type default)
		)
	)
	(wire
		(pts
			(xy 165.1 120.65) (xy 198.12 120.65)
		)
		(stroke
			(width 0)
			(type default)
		)
	)
	(wire
		(pts
			(xy 143.51 156.21) (xy 198.12 156.21)
		)
		(stroke
			(width 0)
			(type default)
		)
	)
	(wire
		(pts
			(xy 245.11 82.55) (xy 245.11 95.25)
		)
		(stroke
			(width 0)
			(type default)
		)
	)
	(wire
		(pts
			(xy 262.89 90.17) (xy 262.89 101.6)
		)
		(stroke
			(width 0)
			(type default)
		)
	)
	(bus
		(pts
			(xy 140.97 161.29) (xy 140.97 163.83)
		)
		(stroke
			(width 0)
			(type default)
		)
	)
	(wire
		(pts
			(xy 156.21 90.17) (xy 198.12 90.17)
		)
		(stroke
			(width 0)
			(type default)
		)
	)
	(wire
		(pts
			(xy 143.51 140.97) (xy 198.12 140.97)
		)
		(stroke
			(width 0)
			(type default)
		)
	)
	(wire
		(pts
			(xy 165.1 105.41) (xy 198.12 105.41)
		)
		(stroke
			(width 0)
			(type default)
		)
	)
	(bus
		(pts
			(xy 135.89 166.37) (xy 138.43 166.37)
		)
		(stroke
			(width 0)
			(type default)
		)
	)
	(bus
		(pts
			(xy 140.97 113.03) (xy 140.97 115.57)
		)
		(stroke
			(width 0)
			(type default)
		)
	)
	(wire
		(pts
			(xy 254 74.93) (xy 254 77.47)
		)
		(stroke
			(width 0)
			(type default)
		)
	)
	(wire
		(pts
			(xy 325.12 139.7) (xy 306.07 139.7)
		)
		(stroke
			(width 0)
			(type default)
		)
	)
	(wire
		(pts
			(xy 245.11 74.93) (xy 245.11 77.47)
		)
		(stroke
			(width 0)
			(type default)
		)
	)
	(bus
		(pts
			(xy 140.97 107.95) (xy 140.97 113.03)
		)
		(stroke
			(width 0)
			(type default)
		)
	)
	(bus
		(pts
			(xy 138.43 166.37) (xy 140.97 163.83)
		)
		(stroke
			(width 0)
			(type default)
		)
	)
	(wire
		(pts
			(xy 143.51 148.59) (xy 168.91 148.59)
		)
		(stroke
			(width 0)
			(type default)
		)
	)
	(bus
		(pts
			(xy 140.97 115.57) (xy 140.97 120.65)
		)
		(stroke
			(width 0)
			(type default)
		)
	)
	(wire
		(pts
			(xy 143.51 110.49) (xy 198.12 110.49)
		)
		(stroke
			(width 0)
			(type default)
		)
	)
	(wire
		(pts
			(xy 143.51 118.11) (xy 168.91 118.11)
		)
		(stroke
			(width 0)
			(type default)
		)
	)
	(wire
		(pts
			(xy 143.51 133.35) (xy 168.91 133.35)
		)
		(stroke
			(width 0)
			(type default)
		)
	)
	(wire
		(pts
			(xy 143.51 113.03) (xy 198.12 113.03)
		)
		(stroke
			(width 0)
			(type default)
		)
	)
	(wire
		(pts
			(xy 233.68 95.25) (xy 245.11 95.25)
		)
		(stroke
			(width 0)
			(type default)
		)
	)
	(wire
		(pts
			(xy 233.68 90.17) (xy 262.89 90.17)
		)
		(stroke
			(width 0)
			(type default)
		)
	)
	(wire
		(pts
			(xy 271.78 144.78) (xy 271.78 149.86)
		)
		(stroke
			(width 0)
			(type default)
		)
	)
	(bus
		(pts
			(xy 140.97 146.05) (xy 140.97 151.13)
		)
		(stroke
			(width 0)
			(type default)
		)
	)
	(wire
		(pts
			(xy 308.61 152.4) (xy 308.61 142.24)
		)
		(stroke
			(width 0)
			(type default)
		)
	)
	(wire
		(pts
			(xy 173.99 102.87) (xy 198.12 102.87)
		)
		(stroke
			(width 0)
			(type default)
		)
	)
	(wire
		(pts
			(xy 271.78 87.63) (xy 271.78 101.6)
		)
		(stroke
			(width 0)
			(type default)
		)
	)
	(bus
		(pts
			(xy 140.97 123.19) (xy 140.97 128.27)
		)
		(stroke
			(width 0)
			(type default)
		)
	)
	(wire
		(pts
			(xy 236.22 74.93) (xy 245.11 74.93)
		)
		(stroke
			(width 0)
			(type default)
		)
	)
	(wire
		(pts
			(xy 233.68 219.71) (xy 251.46 219.71)
		)
		(stroke
			(width 0)
			(type default)
		)
	)
	(bus
		(pts
			(xy 140.97 105.41) (xy 140.97 107.95)
		)
		(stroke
			(width 0)
			(type default)
		)
	)
	(wire
		(pts
			(xy 245.11 95.25) (xy 290.83 95.25)
		)
		(stroke
			(width 0)
			(type default)
		)
	)
	(wire
		(pts
			(xy 167.64 97.79) (xy 198.12 97.79)
		)
		(stroke
			(width 0)
			(type default)
		)
	)
	(wire
		(pts
			(xy 248.92 217.17) (xy 251.46 217.17)
		)
		(stroke
			(width 0)
			(type default)
		)
	)
	(wire
		(pts
			(xy 245.11 74.93) (xy 254 74.93)
		)
		(stroke
			(width 0)
			(type default)
		)
	)
	(wire
		(pts
			(xy 271.78 87.63) (xy 290.83 87.63)
		)
		(stroke
			(width 0)
			(type default)
		)
	)
	(wire
		(pts
			(xy 143.51 158.75) (xy 198.12 158.75)
		)
		(stroke
			(width 0)
			(type default)
		)
	)
	(wire
		(pts
			(xy 165.1 151.13) (xy 198.12 151.13)
		)
		(stroke
			(width 0)
			(type default)
		)
	)
	(wire
		(pts
			(xy 173.99 148.59) (xy 198.12 148.59)
		)
		(stroke
			(width 0)
			(type default)
		)
	)
	(bus
		(pts
			(xy 135.89 105.41) (xy 138.43 105.41)
		)
		(stroke
			(width 0)
			(type default)
		)
	)
	(bus
		(pts
			(xy 140.97 153.67) (xy 140.97 158.75)
		)
		(stroke
			(width 0)
			(type default)
		)
	)
	(bus
		(pts
			(xy 138.43 105.41) (xy 140.97 102.87)
		)
		(stroke
			(width 0)
			(type default)
		)
	)
	(wire
		(pts
			(xy 143.51 120.65) (xy 160.02 120.65)
		)
		(stroke
			(width 0)
			(type default)
		)
	)
	(wire
		(pts
			(xy 143.51 135.89) (xy 160.02 135.89)
		)
		(stroke
			(width 0)
			(type default)
		)
	)
	(wire
		(pts
			(xy 254 82.55) (xy 254 92.71)
		)
		(stroke
			(width 0)
			(type default)
		)
	)
	(wire
		(pts
			(xy 167.64 95.25) (xy 198.12 95.25)
		)
		(stroke
			(width 0)
			(type default)
		)
	)
	(wire
		(pts
			(xy 173.99 133.35) (xy 198.12 133.35)
		)
		(stroke
			(width 0)
			(type default)
		)
	)
	(label "PCIex4.RX3+"
		(at 143.51 156.21 0)
		(effects
			(font
				(size 1.27 1.27)
			)
			(justify left bottom)
		)
	)
	(label "PCIe_JTAG.~{JRST}"
		(at 290.83 87.63 180)
		(effects
			(font
				(size 1.27 1.27)
			)
			(justify right bottom)
		)
	)
	(label "PCIex4.RX2+"
		(at 143.51 140.97 0)
		(effects
			(font
				(size 1.27 1.27)
			)
			(justify left bottom)
		)
	)
	(label "PCIe_JTAG.JTDI"
		(at 290.83 95.25 180)
		(effects
			(font
				(size 1.27 1.27)
			)
			(justify right bottom)
		)
	)
	(label "PCIex4.TX2+"
		(at 143.51 133.35 0)
		(effects
			(font
				(size 1.27 1.27)
			)
			(justify left bottom)
		)
	)
	(label "PCIe_JTAG.JTMS"
		(at 255.27 142.24 0)
		(effects
			(font
				(size 1.27 1.27)
			)
			(justify left bottom)
		)
	)
	(label "PCIe_JTAG.JTMS"
		(at 290.83 92.71 180)
		(effects
			(font
				(size 1.27 1.27)
			)
			(justify right bottom)
		)
	)
	(label "PCIex4.TX2-"
		(at 143.51 135.89 0)
		(effects
			(font
				(size 1.27 1.27)
			)
			(justify left bottom)
		)
	)
	(label "RSENSE"
		(at 234.95 219.71 0)
		(effects
			(font
				(size 1.27 1.27)
			)
			(justify left bottom)
		)
	)
	(label "PCIex4.TX3+"
		(at 143.51 148.59 0)
		(effects
			(font
				(size 1.27 1.27)
			)
			(justify left bottom)
		)
	)
	(label "PCIex4.TX0+"
		(at 143.51 102.87 0)
		(effects
			(font
				(size 1.27 1.27)
			)
			(justify left bottom)
		)
	)
	(label "PCIex4.RX0+"
		(at 143.51 110.49 0)
		(effects
			(font
				(size 1.27 1.27)
			)
			(justify left bottom)
		)
	)
	(label "PCIe_{x4}_AC.TX0-"
		(at 195.58 105.41 180)
		(effects
			(font
				(size 1.27 1.27)
			)
			(justify right bottom)
		)
	)
	(label "REFCLK.-"
		(at 156.21 97.79 180)
		(effects
			(font
				(size 1.27 1.27)
			)
			(justify right bottom)
		)
	)
	(label "PCIex4.RX1+"
		(at 143.51 125.73 0)
		(effects
			(font
				(size 1.27 1.27)
			)
			(justify left bottom)
		)
	)
	(label "PCIe_{x4}_AC.TX0+"
		(at 195.58 102.87 180)
		(effects
			(font
				(size 1.27 1.27)
			)
			(justify right bottom)
		)
	)
	(label "PCIex4.TX3-"
		(at 143.51 151.13 0)
		(effects
			(font
				(size 1.27 1.27)
			)
			(justify left bottom)
		)
	)
	(label "PCIe_{x4}_AC.TX2-"
		(at 195.58 135.89 180)
		(effects
			(font
				(size 1.27 1.27)
			)
			(justify right bottom)
		)
	)
	(label "PCIe_JTAG.JTCK"
		(at 290.83 90.17 180)
		(effects
			(font
				(size 1.27 1.27)
			)
			(justify right bottom)
		)
	)
	(label "PCIe_JTAG.JTDO"
		(at 325.12 149.86 180)
		(effects
			(font
				(size 1.27 1.27)
			)
			(justify right bottom)
		)
	)
	(label "PCIe_JTAG.JTDI"
		(at 325.12 144.78 180)
		(effects
			(font
				(size 1.27 1.27)
			)
			(justify right bottom)
		)
	)
	(label "PCIe_{x4}_AC.TX3+"
		(at 195.58 148.59 180)
		(effects
			(font
				(size 1.27 1.27)
			)
			(justify right bottom)
		)
	)
	(label "PCIe_{x4}_AC.TX2+"
		(at 195.58 133.35 180)
		(effects
			(font
				(size 1.27 1.27)
			)
			(justify right bottom)
		)
	)
	(label "REFCLK.+"
		(at 156.21 95.25 180)
		(effects
			(font
				(size 1.27 1.27)
			)
			(justify right bottom)
		)
	)
	(label "RBIAS"
		(at 234.95 217.17 0)
		(effects
			(font
				(size 1.27 1.27)
			)
			(justify left bottom)
		)
	)
	(label "PCIex4.RX2-"
		(at 143.51 143.51 0)
		(effects
			(font
				(size 1.27 1.27)
			)
			(justify left bottom)
		)
	)
	(label "PCIex4.TX1-"
		(at 143.51 120.65 0)
		(effects
			(font
				(size 1.27 1.27)
			)
			(justify left bottom)
		)
	)
	(label "PCIe_JTAG.~{JRST}"
		(at 325.12 139.7 180)
		(effects
			(font
				(size 1.27 1.27)
			)
			(justify right bottom)
		)
	)
	(label "PCIe_JTAG.JTDO"
		(at 290.83 97.79 180)
		(effects
			(font
				(size 1.27 1.27)
			)
			(justify right bottom)
		)
	)
	(label "CLK-"
		(at 180.34 97.79 180)
		(effects
			(font
				(size 1.27 1.27)
			)
			(justify right bottom)
		)
	)
	(label "PCIex4.TX0-"
		(at 143.51 105.41 0)
		(effects
			(font
				(size 1.27 1.27)
			)
			(justify left bottom)
		)
	)
	(label "PCIex4.TX1+"
		(at 143.51 118.11 0)
		(effects
			(font
				(size 1.27 1.27)
			)
			(justify left bottom)
		)
	)
	(label "PCIe_JTAG.JTCK"
		(at 255.27 147.32 0)
		(effects
			(font
				(size 1.27 1.27)
			)
			(justify left bottom)
		)
	)
	(label "PCIe_{x4}_AC.TX3-"
		(at 195.58 151.13 180)
		(effects
			(font
				(size 1.27 1.27)
			)
			(justify right bottom)
		)
	)
	(label "PCIe_{x4}_AC.TX1+"
		(at 195.58 118.11 180)
		(effects
			(font
				(size 1.27 1.27)
			)
			(justify right bottom)
		)
	)
	(label "PCIex4.RX1-"
		(at 143.51 128.27 0)
		(effects
			(font
				(size 1.27 1.27)
			)
			(justify left bottom)
		)
	)
	(label "PCIex4.RX3-"
		(at 143.51 158.75 0)
		(effects
			(font
				(size 1.27 1.27)
			)
			(justify left bottom)
		)
	)
	(label "PCIe_{x4}_AC.TX1-"
		(at 195.58 120.65 180)
		(effects
			(font
				(size 1.27 1.27)
			)
			(justify right bottom)
		)
	)
	(label "PCIex4.RX0-"
		(at 143.51 113.03 0)
		(effects
			(font
				(size 1.27 1.27)
			)
			(justify left bottom)
		)
	)
	(label "CLK+"
		(at 180.34 95.25 180)
		(effects
			(font
				(size 1.27 1.27)
			)
			(justify right bottom)
		)
	)
	(hierarchical_label "REFCLK{CLK}"
		(shape input)
		(at 135.89 105.41 180)
		(effects
			(font
				(size 1.27 1.27)
			)
			(justify right)
		)
	)
	(hierarchical_label "~{PE_RST}"
		(shape input)
		(at 156.21 87.63 180)
		(effects
			(font
				(size 1.27 1.27)
			)
			(justify right)
		)
	)
	(hierarchical_label "PCIex4{PCIe}"
		(shape bidirectional)
		(at 135.89 166.37 180)
		(effects
			(font
				(size 1.27 1.27)
			)
			(justify right)
		)
	)
	(hierarchical_label "~{PE_WAKE}"
		(shape output)
		(at 156.21 90.17 180)
		(effects
			(font
				(size 1.27 1.27)
			)
			(justify right)
		)
	)
	(rule_area
		(polyline
			(pts
				(xy 139.7 92.71) (xy 196.85 92.71) (xy 196.85 160.02) (xy 139.7 160.02)
			)
			(stroke
				(width 0)
				(type dash)
			)
			(fill
				(type none)
			)
		)
	)
	(netclass_flag ""
		(length 2.54)
		(shape round)
		(at 139.7 92.71 0)
		(fields_autoplaced yes)
		(effects
			(font
				(size 1.27 1.27)
			)
			(justify left bottom)
		)
		(property "Netclass" "85Ohm-diff_PCIe"
			(at 139.0015 90.17 0)
			(effects
				(font
					(size 1.27 1.27)
				)
				(justify right)
			)
		)
		(property "Component Class" ""
			(at -83.82 39.37 0)
			(effects
				(font
					(size 1.27 1.27)
					(italic yes)
				)
				(justify right)
			)
		)
	)
	(symbol
		(lib_id "antmicroResistors0402:R_8k2_0402")
		(at 254 82.55 90)
		(unit 1)
		(exclude_from_sim no)
		(in_bom yes)
		(on_board yes)
		(dnp no)
		(property "Reference" "R118"
			(at 255.524 78.74 90)
			(effects
				(font
					(size 1.27 1.27)
					(thickness 0.15)
				)
				(justify right)
			)
		)
		(property "Value" "R_8k2_0402"
			(at 266.7 62.23 0)
			(effects
				(font
					(size 1.27 1.27)
					(thickness 0.15)
				)
				(justify left bottom)
				(hide yes)
			)
		)
		(property "Footprint" "antmicro-footprints:R_0402_1005Metric"
			(at 269.24 62.23 0)
			(effects
				(font
					(size 1.27 1.27)
					(thickness 0.15)
				)
				(justify left bottom)
				(hide yes)
			)
		)
		(property "Datasheet" "https://www.bourns.com/docs/product-datasheets/cr.pdf"
			(at 271.78 62.23 0)
			(effects
				(font
					(size 1.27 1.27)
					(thickness 0.15)
				)
				(justify left bottom)
				(hide yes)
			)
		)
		(property "Description" "SMD Chip Resistor"
			(at 254 82.55 0)
			(effects
				(font
					(size 1.27 1.27)
				)
				(hide yes)
			)
		)
		(property "MPN" "CR0402-FX-8201GLF"
			(at 274.32 62.23 0)
			(effects
				(font
					(size 1.27 1.27)
					(thickness 0.15)
				)
				(justify left bottom)
				(hide yes)
			)
		)
		(property "Manufacturer" "Bourns"
			(at 276.86 62.23 0)
			(effects
				(font
					(size 1.27 1.27)
					(thickness 0.15)
				)
				(justify left bottom)
				(hide yes)
			)
		)
		(property "License" "Apache-2.0"
			(at 279.4 62.23 0)
			(effects
				(font
					(size 1.27 1.27)
					(thickness 0.15)
				)
				(justify left bottom)
				(hide yes)
			)
		)
		(property "Author" "Antmicro"
			(at 281.94 62.23 0)
			(effects
				(font
					(size 1.27 1.27)
					(thickness 0.15)
				)
				(justify left bottom)
				(hide yes)
			)
		)
		(property "Val" "8k2"
			(at 255.524 81.28 90)
			(effects
				(font
					(size 1.27 1.27)
					(thickness 0.15)
				)
				(justify right)
			)
		)
		(property "Tolerance" "1%"
			(at 264.16 62.23 0)
			(effects
				(font
					(size 1.27 1.27)
				)
				(justify left bottom)
				(hide yes)
			)
		)
		(pin "1"
		)
		(pin "2"
		)
		(instances
			(project "OCuLink to 10GbE adapter"
				(path ""
					(reference "R53")
					(unit 1)
				)
			)
			(project "thunderbolt-to-10gbe-adapter"
				(path ""
					(reference "R118")
					(unit 1)
				)
			)
		)
	)
	(symbol
		(lib_id "antmicroCapacitors0402:C_220n_16V_0402")
		(at 168.91 148.59 0)
		(unit 1)
		(exclude_from_sim no)
		(in_bom yes)
		(on_board yes)
		(dnp no)
		(property "Reference" "C273"
			(at 170.18 147.32 0)
			(effects
				(font
					(size 1.27 1.27)
					(thickness 0.15)
				)
				(justify right)
			)
		)
		(property "Value" "C_220n_16V_0402"
			(at 189.23 158.75 0)
			(effects
				(font
					(size 1.27 1.27)
					(thickness 0.15)
				)
				(justify left bottom)
				(hide yes)
			)
		)
		(property "Footprint" "antmicro-footprints:C_0402_1005Metric"
			(at 189.23 161.29 0)
			(effects
				(font
					(size 1.27 1.27)
					(thickness 0.15)
				)
				(justify left bottom)
				(hide yes)
			)
		)
		(property "Datasheet" "https://www.murata.com/products/productdetail?partno=GRM155R71C224KA12%23"
			(at 189.23 163.83 0)
			(effects
				(font
					(size 1.27 1.27)
					(thickness 0.15)
				)
				(justify left bottom)
				(hide yes)
			)
		)
		(property "Description" "SMD Multilayer Ceramic Capacitor, 0.22 µF, 16 V, 0402 [1005 Metric], ± 10%, X7R, GRM Series"
			(at 168.91 148.59 0)
			(effects
				(font
					(size 1.27 1.27)
				)
				(hide yes)
			)
		)
		(property "MPN" "GRM155R71C224KA12D"
			(at 189.23 166.37 0)
			(effects
				(font
					(size 1.27 1.27)
					(thickness 0.15)
				)
				(justify left bottom)
				(hide yes)
			)
		)
		(property "Manufacturer" "Murata"
			(at 189.23 168.91 0)
			(effects
				(font
					(size 1.27 1.27)
					(thickness 0.15)
				)
				(justify left bottom)
				(hide yes)
			)
		)
		(property "License" "Apache-2.0"
			(at 189.23 171.45 0)
			(effects
				(font
					(size 1.27 1.27)
					(thickness 0.15)
				)
				(justify left bottom)
				(hide yes)
			)
		)
		(property "Author" "Antmicro"
			(at 189.23 173.99 0)
			(effects
				(font
					(size 1.27 1.27)
					(thickness 0.15)
				)
				(justify left bottom)
				(hide yes)
			)
		)
		(property "Val" "220n"
			(at 172.72 147.32 0)
			(effects
				(font
					(size 1.27 1.27)
					(thickness 0.15)
				)
				(justify left)
			)
		)
		(property "Voltage" "16V"
			(at 189.23 176.53 0)
			(effects
				(font
					(size 1.27 1.27)
				)
				(justify left bottom)
				(hide yes)
			)
		)
		(property "Dielectric" "X7R"
			(at 189.23 179.07 0)
			(effects
				(font
					(size 1.27 1.27)
				)
				(justify left bottom)
				(hide yes)
			)
		)
		(pin "2"
		)
		(pin "1"
		)
		(instances
			(project "OCuLink to 10GbE adapter"
				(path ""
					(reference "C196")
					(unit 1)
				)
			)
			(project "thunderbolt-to-10gbe-adapter"
				(path ""
					(reference "C273")
					(unit 1)
				)
			)
		)
	)
	(symbol
		(lib_id "antmicroResistors0402:R_0R_0402")
		(at 162.56 95.25 0)
		(unit 1)
		(exclude_from_sim no)
		(in_bom yes)
		(on_board yes)
		(dnp no)
		(property "Reference" "R113"
			(at 159.512 94.234 0)
			(effects
				(font
					(size 1.27 1.27)
					(thickness 0.15)
				)
			)
		)
		(property "Value" "R_0R_0402"
			(at 182.88 107.95 0)
			(effects
				(font
					(size 1.27 1.27)
					(thickness 0.15)
				)
				(justify left bottom)
				(hide yes)
			)
		)
		(property "Footprint" "antmicro-footprints:R_0402_1005Metric"
			(at 182.88 110.49 0)
			(effects
				(font
					(size 1.27 1.27)
					(thickness 0.15)
				)
				(justify left bottom)
				(hide yes)
			)
		)
		(property "Datasheet" "https://industrial.panasonic.com/cdbs/www-data/pdf/RDA0000/AOA0000C301.pdf"
			(at 182.88 113.03 0)
			(effects
				(font
					(size 1.27 1.27)
					(thickness 0.15)
				)
				(justify left bottom)
				(hide yes)
			)
		)
		(property "Description" "SMD Chip Resistor, Jumper, 0 ohm, 100 mW, 0402 [1005 Metric], Thick Film, General Purpose"
			(at 182.88 128.27 0)
			(effects
				(font
					(size 1.27 1.27)
				)
				(justify left bottom)
				(hide yes)
			)
		)
		(property "MPN" "ERJ2GE0R00X"
			(at 182.88 115.57 0)
			(effects
				(font
					(size 1.27 1.27)
					(thickness 0.15)
				)
				(justify left bottom)
				(hide yes)
			)
		)
		(property "Manufacturer" "Panasonic"
			(at 182.88 118.11 0)
			(effects
				(font
					(size 1.27 1.27)
					(thickness 0.15)
				)
				(justify left bottom)
				(hide yes)
			)
		)
		(property "License" "Apache-2.0"
			(at 182.88 120.65 0)
			(effects
				(font
					(size 1.27 1.27)
					(thickness 0.15)
				)
				(justify left bottom)
				(hide yes)
			)
		)
		(property "Author" "Antmicro"
			(at 182.88 123.19 0)
			(effects
				(font
					(size 1.27 1.27)
					(thickness 0.15)
				)
				(justify left bottom)
				(hide yes)
			)
		)
		(property "Val" "0R"
			(at 168.91 94.234 0)
			(effects
				(font
					(size 1.27 1.27)
					(thickness 0.15)
				)
			)
		)
		(property "Tolerance" "~"
			(at 182.88 105.41 0)
			(effects
				(font
					(size 1.27 1.27)
				)
				(justify left bottom)
				(hide yes)
			)
		)
		(property "Current" "1A"
			(at 182.88 125.73 0)
			(effects
				(font
					(size 1.27 1.27)
					(thickness 0.15)
				)
				(justify left bottom)
				(hide yes)
			)
		)
		(pin "2"
		)
		(pin "1"
		)
		(instances
			(project "oculink-to-10gbe-adapter"
				(path ""
					(reference "R95")
					(unit 1)
				)
			)
			(project "thunderbolt-to-10gbe-adapter"
				(path ""
					(reference "R113")
					(unit 1)
				)
			)
		)
	)
	(symbol
		(lib_id "antmicropower:+3V3")
		(at 254 72.39 0)
		(unit 1)
		(exclude_from_sim no)
		(in_bom yes)
		(on_board yes)
		(dnp no)
		(property "Reference" "#PWR0352"
			(at 269.24 72.39 0)
			(effects
				(font
					(size 1.27 1.27)
					(thickness 0.15)
				)
				(justify left bottom)
				(hide yes)
			)
		)
		(property "Value" "+3V3"
			(at 254 68.58 0)
			(effects
				(font
					(size 1.27 1.27)
					(thickness 0.15)
				)
			)
		)
		(property "Footprint" ""
			(at 269.24 80.01 0)
			(effects
				(font
					(size 1.27 1.27)
					(thickness 0.15)
				)
				(justify left bottom)
				(hide yes)
			)
		)
		(property "Datasheet" ""
			(at 269.24 82.55 0)
			(effects
				(font
					(size 1.27 1.27)
					(thickness 0.15)
				)
				(justify left bottom)
				(hide yes)
			)
		)
		(property "Description" ""
			(at 254 72.39 0)
			(effects
				(font
					(size 1.27 1.27)
				)
				(hide yes)
			)
		)
		(property "Author" "Antmicro"
			(at 269.24 74.93 0)
			(effects
				(font
					(size 1.27 1.27)
					(thickness 0.15)
				)
				(justify left bottom)
				(hide yes)
			)
		)
		(property "License" "Apache-2.0"
			(at 269.24 77.47 0)
			(effects
				(font
					(size 1.27 1.27)
					(thickness 0.15)
				)
				(justify left bottom)
				(hide yes)
			)
		)
		(pin "1"
		)
		(instances
			(project "OCuLink to 10GbE adapter"
				(path ""
					(reference "#PWR0245")
					(unit 1)
				)
			)
			(project "thunderbolt-to-10gbe-adapter"
				(path ""
					(reference "#PWR0352")
					(unit 1)
				)
			)
		)
	)
	(symbol
		(lib_id "antmicroResistors0402:R_4k75_0.5%_0402")
		(at 243.84 217.17 0)
		(unit 1)
		(exclude_from_sim no)
		(in_bom yes)
		(on_board yes)
		(dnp no)
		(property "Reference" "R116"
			(at 246.38 212.09 0)
			(effects
				(font
					(size 1.27 1.27)
					(thickness 0.15)
				)
			)
		)
		(property "Value" "R_4k75_0.5%_0402"
			(at 264.16 229.87 0)
			(effects
				(font
					(size 1.27 1.27)
					(thickness 0.15)
				)
				(justify left bottom)
				(hide yes)
			)
		)
		(property "Footprint" "antmicro-footprints:R_0402_1005Metric"
			(at 264.16 232.41 0)
			(effects
				(font
					(size 1.27 1.27)
					(thickness 0.15)
				)
				(justify left bottom)
				(hide yes)
			)
		)
		(property "Datasheet" "https://industrial.panasonic.com/cdbs/www-data/pdf/RDQ0000/ast-ind-151033.pdf"
			(at 264.16 234.95 0)
			(effects
				(font
					(size 1.27 1.27)
					(thickness 0.15)
				)
				(justify left bottom)
				(hide yes)
			)
		)
		(property "Description" "SMD Chip Resistor, 4.75 kohm, ± 0.5%, 100 mW, 0402 [1005 Metric], Thick Film, High Temperature"
			(at 243.84 217.17 0)
			(effects
				(font
					(size 1.27 1.27)
				)
				(hide yes)
			)
		)
		(property "MPN" "ERJ-H2RD4751X"
			(at 264.16 237.49 0)
			(effects
				(font
					(size 1.27 1.27)
					(thickness 0.15)
				)
				(justify left bottom)
				(hide yes)
			)
		)
		(property "Manufacturer" "Panasonic"
			(at 264.16 240.03 0)
			(effects
				(font
					(size 1.27 1.27)
					(thickness 0.15)
				)
				(justify left bottom)
				(hide yes)
			)
		)
		(property "License" "Apache-2.0"
			(at 264.16 242.57 0)
			(effects
				(font
					(size 1.27 1.27)
					(thickness 0.15)
				)
				(justify left bottom)
				(hide yes)
			)
		)
		(property "Author" "Antmicro"
			(at 264.16 245.11 0)
			(effects
				(font
					(size 1.27 1.27)
					(thickness 0.15)
				)
				(justify left bottom)
				(hide yes)
			)
		)
		(property "Val" "4k75"
			(at 246.38 214.63 0)
			(effects
				(font
					(size 1.27 1.27)
					(thickness 0.15)
				)
			)
		)
		(property "Tolerance" "0.5%"
			(at 264.16 227.33 0)
			(effects
				(font
					(size 1.27 1.27)
				)
				(justify left bottom)
				(hide yes)
			)
		)
		(pin "1"
		)
		(pin "2"
		)
		(instances
			(project "OCuLink to 10GbE adapter"
				(path ""
					(reference "R56")
					(unit 1)
				)
			)
			(project "thunderbolt-to-10gbe-adapter"
				(path ""
					(reference "R116")
					(unit 1)
				)
			)
		)
	)
	(symbol
		(lib_id "antmicroCapacitors0402:C_220n_16V_0402")
		(at 168.91 133.35 0)
		(unit 1)
		(exclude_from_sim no)
		(in_bom yes)
		(on_board yes)
		(dnp no)
		(property "Reference" "C272"
			(at 170.18 132.08 0)
			(effects
				(font
					(size 1.27 1.27)
					(thickness 0.15)
				)
				(justify right)
			)
		)
		(property "Value" "C_220n_16V_0402"
			(at 189.23 143.51 0)
			(effects
				(font
					(size 1.27 1.27)
					(thickness 0.15)
				)
				(justify left bottom)
				(hide yes)
			)
		)
		(property "Footprint" "antmicro-footprints:C_0402_1005Metric"
			(at 189.23 146.05 0)
			(effects
				(font
					(size 1.27 1.27)
					(thickness 0.15)
				)
				(justify left bottom)
				(hide yes)
			)
		)
		(property "Datasheet" "https://www.murata.com/products/productdetail?partno=GRM155R71C224KA12%23"
			(at 189.23 148.59 0)
			(effects
				(font
					(size 1.27 1.27)
					(thickness 0.15)
				)
				(justify left bottom)
				(hide yes)
			)
		)
		(property "Description" "SMD Multilayer Ceramic Capacitor, 0.22 µF, 16 V, 0402 [1005 Metric], ± 10%, X7R, GRM Series"
			(at 168.91 133.35 0)
			(effects
				(font
					(size 1.27 1.27)
				)
				(hide yes)
			)
		)
		(property "MPN" "GRM155R71C224KA12D"
			(at 189.23 151.13 0)
			(effects
				(font
					(size 1.27 1.27)
					(thickness 0.15)
				)
				(justify left bottom)
				(hide yes)
			)
		)
		(property "Manufacturer" "Murata"
			(at 189.23 153.67 0)
			(effects
				(font
					(size 1.27 1.27)
					(thickness 0.15)
				)
				(justify left bottom)
				(hide yes)
			)
		)
		(property "License" "Apache-2.0"
			(at 189.23 156.21 0)
			(effects
				(font
					(size 1.27 1.27)
					(thickness 0.15)
				)
				(justify left bottom)
				(hide yes)
			)
		)
		(property "Author" "Antmicro"
			(at 189.23 158.75 0)
			(effects
				(font
					(size 1.27 1.27)
					(thickness 0.15)
				)
				(justify left bottom)
				(hide yes)
			)
		)
		(property "Val" "220n"
			(at 172.72 132.08 0)
			(effects
				(font
					(size 1.27 1.27)
					(thickness 0.15)
				)
				(justify left)
			)
		)
		(property "Voltage" "16V"
			(at 189.23 161.29 0)
			(effects
				(font
					(size 1.27 1.27)
				)
				(justify left bottom)
				(hide yes)
			)
		)
		(property "Dielectric" "X7R"
			(at 189.23 163.83 0)
			(effects
				(font
					(size 1.27 1.27)
				)
				(justify left bottom)
				(hide yes)
			)
		)
		(pin "2"
		)
		(pin "1"
		)
		(instances
			(project "OCuLink to 10GbE adapter"
				(path ""
					(reference "C194")
					(unit 1)
				)
			)
			(project "thunderbolt-to-10gbe-adapter"
				(path ""
					(reference "C272")
					(unit 1)
				)
			)
		)
	)
	(symbol
		(lib_id "antmicroCapacitors0402:C_220n_16V_0402")
		(at 160.02 135.89 0)
		(unit 1)
		(exclude_from_sim no)
		(in_bom yes)
		(on_board yes)
		(dnp no)
		(property "Reference" "C268"
			(at 161.29 134.62 0)
			(effects
				(font
					(size 1.27 1.27)
					(thickness 0.15)
				)
				(justify right)
			)
		)
		(property "Value" "C_220n_16V_0402"
			(at 180.34 146.05 0)
			(effects
				(font
					(size 1.27 1.27)
					(thickness 0.15)
				)
				(justify left bottom)
				(hide yes)
			)
		)
		(property "Footprint" "antmicro-footprints:C_0402_1005Metric"
			(at 180.34 148.59 0)
			(effects
				(font
					(size 1.27 1.27)
					(thickness 0.15)
				)
				(justify left bottom)
				(hide yes)
			)
		)
		(property "Datasheet" "https://www.murata.com/products/productdetail?partno=GRM155R71C224KA12%23"
			(at 180.34 151.13 0)
			(effects
				(font
					(size 1.27 1.27)
					(thickness 0.15)
				)
				(justify left bottom)
				(hide yes)
			)
		)
		(property "Description" "SMD Multilayer Ceramic Capacitor, 0.22 µF, 16 V, 0402 [1005 Metric], ± 10%, X7R, GRM Series"
			(at 160.02 135.89 0)
			(effects
				(font
					(size 1.27 1.27)
				)
				(hide yes)
			)
		)
		(property "MPN" "GRM155R71C224KA12D"
			(at 180.34 153.67 0)
			(effects
				(font
					(size 1.27 1.27)
					(thickness 0.15)
				)
				(justify left bottom)
				(hide yes)
			)
		)
		(property "Manufacturer" "Murata"
			(at 180.34 156.21 0)
			(effects
				(font
					(size 1.27 1.27)
					(thickness 0.15)
				)
				(justify left bottom)
				(hide yes)
			)
		)
		(property "License" "Apache-2.0"
			(at 180.34 158.75 0)
			(effects
				(font
					(size 1.27 1.27)
					(thickness 0.15)
				)
				(justify left bottom)
				(hide yes)
			)
		)
		(property "Author" "Antmicro"
			(at 180.34 161.29 0)
			(effects
				(font
					(size 1.27 1.27)
					(thickness 0.15)
				)
				(justify left bottom)
				(hide yes)
			)
		)
		(property "Val" "220n"
			(at 163.83 134.62 0)
			(effects
				(font
					(size 1.27 1.27)
					(thickness 0.15)
				)
				(justify left)
			)
		)
		(property "Voltage" "16V"
			(at 180.34 163.83 0)
			(effects
				(font
					(size 1.27 1.27)
				)
				(justify left bottom)
				(hide yes)
			)
		)
		(property "Dielectric" "X7R"
			(at 180.34 166.37 0)
			(effects
				(font
					(size 1.27 1.27)
				)
				(justify left bottom)
				(hide yes)
			)
		)
		(pin "2"
		)
		(pin "1"
		)
		(instances
			(project "OCuLink to 10GbE adapter"
				(path ""
					(reference "C195")
					(unit 1)
				)
			)
			(project "thunderbolt-to-10gbe-adapter"
				(path ""
					(reference "C268")
					(unit 1)
				)
			)
		)
	)
	(symbol
		(lib_id "antmicroResistors0402:R_8k2_0402")
		(at 245.11 82.55 90)
		(unit 1)
		(exclude_from_sim no)
		(in_bom yes)
		(on_board yes)
		(dnp no)
		(property "Reference" "R117"
			(at 246.634 78.74 90)
			(effects
				(font
					(size 1.27 1.27)
					(thickness 0.15)
				)
				(justify right)
			)
		)
		(property "Value" "R_8k2_0402"
			(at 257.81 62.23 0)
			(effects
				(font
					(size 1.27 1.27)
					(thickness 0.15)
				)
				(justify left bottom)
				(hide yes)
			)
		)
		(property "Footprint" "antmicro-footprints:R_0402_1005Metric"
			(at 260.35 62.23 0)
			(effects
				(font
					(size 1.27 1.27)
					(thickness 0.15)
				)
				(justify left bottom)
				(hide yes)
			)
		)
		(property "Datasheet" "https://www.bourns.com/docs/product-datasheets/cr.pdf"
			(at 262.89 62.23 0)
			(effects
				(font
					(size 1.27 1.27)
					(thickness 0.15)
				)
				(justify left bottom)
				(hide yes)
			)
		)
		(property "Description" "SMD Chip Resistor"
			(at 245.11 82.55 0)
			(effects
				(font
					(size 1.27 1.27)
				)
				(hide yes)
			)
		)
		(property "MPN" "CR0402-FX-8201GLF"
			(at 265.43 62.23 0)
			(effects
				(font
					(size 1.27 1.27)
					(thickness 0.15)
				)
				(justify left bottom)
				(hide yes)
			)
		)
		(property "Manufacturer" "Bourns"
			(at 267.97 62.23 0)
			(effects
				(font
					(size 1.27 1.27)
					(thickness 0.15)
				)
				(justify left bottom)
				(hide yes)
			)
		)
		(property "License" "Apache-2.0"
			(at 270.51 62.23 0)
			(effects
				(font
					(size 1.27 1.27)
					(thickness 0.15)
				)
				(justify left bottom)
				(hide yes)
			)
		)
		(property "Author" "Antmicro"
			(at 273.05 62.23 0)
			(effects
				(font
					(size 1.27 1.27)
					(thickness 0.15)
				)
				(justify left bottom)
				(hide yes)
			)
		)
		(property "Val" "8k2"
			(at 246.634 81.28 90)
			(effects
				(font
					(size 1.27 1.27)
					(thickness 0.15)
				)
				(justify right)
			)
		)
		(property "Tolerance" "1%"
			(at 255.27 62.23 0)
			(effects
				(font
					(size 1.27 1.27)
				)
				(justify left bottom)
				(hide yes)
			)
		)
		(pin "1"
		)
		(pin "2"
		)
		(instances
			(project "OCuLink to 10GbE adapter"
				(path ""
					(reference "R52")
					(unit 1)
				)
			)
			(project "thunderbolt-to-10gbe-adapter"
				(path ""
					(reference "R117")
					(unit 1)
				)
			)
		)
	)
	(symbol
		(lib_id "antmicroCapacitors0402:C_220n_16V_0402")
		(at 160.02 105.41 0)
		(unit 1)
		(exclude_from_sim no)
		(in_bom yes)
		(on_board yes)
		(dnp no)
		(property "Reference" "C266"
			(at 161.29 104.14 0)
			(effects
				(font
					(size 1.27 1.27)
					(thickness 0.15)
				)
				(justify right)
			)
		)
		(property "Value" "C_220n_16V_0402"
			(at 180.34 115.57 0)
			(effects
				(font
					(size 1.27 1.27)
					(thickness 0.15)
				)
				(justify left bottom)
				(hide yes)
			)
		)
		(property "Footprint" "antmicro-footprints:C_0402_1005Metric"
			(at 180.34 118.11 0)
			(effects
				(font
					(size 1.27 1.27)
					(thickness 0.15)
				)
				(justify left bottom)
				(hide yes)
			)
		)
		(property "Datasheet" "https://www.murata.com/products/productdetail?partno=GRM155R71C224KA12%23"
			(at 180.34 120.65 0)
			(effects
				(font
					(size 1.27 1.27)
					(thickness 0.15)
				)
				(justify left bottom)
				(hide yes)
			)
		)
		(property "Description" "SMD Multilayer Ceramic Capacitor, 0.22 µF, 16 V, 0402 [1005 Metric], ± 10%, X7R, GRM Series"
			(at 160.02 105.41 0)
			(effects
				(font
					(size 1.27 1.27)
				)
				(hide yes)
			)
		)
		(property "MPN" "GRM155R71C224KA12D"
			(at 180.34 123.19 0)
			(effects
				(font
					(size 1.27 1.27)
					(thickness 0.15)
				)
				(justify left bottom)
				(hide yes)
			)
		)
		(property "Manufacturer" "Murata"
			(at 180.34 125.73 0)
			(effects
				(font
					(size 1.27 1.27)
					(thickness 0.15)
				)
				(justify left bottom)
				(hide yes)
			)
		)
		(property "License" "Apache-2.0"
			(at 180.34 128.27 0)
			(effects
				(font
					(size 1.27 1.27)
					(thickness 0.15)
				)
				(justify left bottom)
				(hide yes)
			)
		)
		(property "Author" "Antmicro"
			(at 180.34 130.81 0)
			(effects
				(font
					(size 1.27 1.27)
					(thickness 0.15)
				)
				(justify left bottom)
				(hide yes)
			)
		)
		(property "Val" "220n"
			(at 163.83 104.14 0)
			(effects
				(font
					(size 1.27 1.27)
					(thickness 0.15)
				)
				(justify left)
			)
		)
		(property "Voltage" "16V"
			(at 180.34 133.35 0)
			(effects
				(font
					(size 1.27 1.27)
				)
				(justify left bottom)
				(hide yes)
			)
		)
		(property "Dielectric" "X7R"
			(at 180.34 135.89 0)
			(effects
				(font
					(size 1.27 1.27)
				)
				(justify left bottom)
				(hide yes)
			)
		)
		(pin "2"
		)
		(pin "1"
		)
		(instances
			(project "OCuLink to 10GbE adapter"
				(path ""
					(reference "C191")
					(unit 1)
				)
			)
			(project "thunderbolt-to-10gbe-adapter"
				(path ""
					(reference "C266")
					(unit 1)
				)
			)
		)
	)
	(symbol
		(lib_id "antmicroResistors0402:R_8k2_0402")
		(at 271.78 106.68 90)
		(unit 1)
		(exclude_from_sim no)
		(in_bom yes)
		(on_board yes)
		(dnp no)
		(property "Reference" "R120"
			(at 273.304 102.87 90)
			(effects
				(font
					(size 1.27 1.27)
					(thickness 0.15)
				)
				(justify right)
			)
		)
		(property "Value" "R_8k2_0402"
			(at 284.48 86.36 0)
			(effects
				(font
					(size 1.27 1.27)
					(thickness 0.15)
				)
				(justify left bottom)
				(hide yes)
			)
		)
		(property "Footprint" "antmicro-footprints:R_0402_1005Metric"
			(at 287.02 86.36 0)
			(effects
				(font
					(size 1.27 1.27)
					(thickness 0.15)
				)
				(justify left bottom)
				(hide yes)
			)
		)
		(property "Datasheet" "https://www.bourns.com/docs/product-datasheets/cr.pdf"
			(at 289.56 86.36 0)
			(effects
				(font
					(size 1.27 1.27)
					(thickness 0.15)
				)
				(justify left bottom)
				(hide yes)
			)
		)
		(property "Description" "SMD Chip Resistor"
			(at 271.78 106.68 0)
			(effects
				(font
					(size 1.27 1.27)
				)
				(hide yes)
			)
		)
		(property "MPN" "CR0402-FX-8201GLF"
			(at 292.1 86.36 0)
			(effects
				(font
					(size 1.27 1.27)
					(thickness 0.15)
				)
				(justify left bottom)
				(hide yes)
			)
		)
		(property "Manufacturer" "Bourns"
			(at 294.64 86.36 0)
			(effects
				(font
					(size 1.27 1.27)
					(thickness 0.15)
				)
				(justify left bottom)
				(hide yes)
			)
		)
		(property "License" "Apache-2.0"
			(at 297.18 86.36 0)
			(effects
				(font
					(size 1.27 1.27)
					(thickness 0.15)
				)
				(justify left bottom)
				(hide yes)
			)
		)
		(property "Author" "Antmicro"
			(at 299.72 86.36 0)
			(effects
				(font
					(size 1.27 1.27)
					(thickness 0.15)
				)
				(justify left bottom)
				(hide yes)
			)
		)
		(property "Val" "8k2"
			(at 273.304 105.41 90)
			(effects
				(font
					(size 1.27 1.27)
					(thickness 0.15)
				)
				(justify right)
			)
		)
		(property "Tolerance" "1%"
			(at 281.94 86.36 0)
			(effects
				(font
					(size 1.27 1.27)
				)
				(justify left bottom)
				(hide yes)
			)
		)
		(pin "1"
		)
		(pin "2"
		)
		(instances
			(project "OCuLink to 10GbE adapter"
				(path ""
					(reference "R55")
					(unit 1)
				)
			)
			(project "thunderbolt-to-10gbe-adapter"
				(path ""
					(reference "R120")
					(unit 1)
				)
			)
		)
	)
	(symbol
		(lib_id "antmicropower:GND")
		(at 262.89 109.22 0)
		(unit 1)
		(exclude_from_sim no)
		(in_bom yes)
		(on_board yes)
		(dnp no)
		(property "Reference" "#PWR0353"
			(at 271.78 111.76 0)
			(effects
				(font
					(size 1.27 1.27)
					(thickness 0.15)
				)
				(justify left bottom)
				(hide yes)
			)
		)
		(property "Value" "GND"
			(at 262.89 113.03 0)
			(effects
				(font
					(size 1.27 1.27)
					(thickness 0.15)
				)
			)
		)
		(property "Footprint" ""
			(at 271.78 116.84 0)
			(effects
				(font
					(size 1.27 1.27)
					(thickness 0.15)
				)
				(justify left bottom)
				(hide yes)
			)
		)
		(property "Datasheet" ""
			(at 271.78 121.92 0)
			(effects
				(font
					(size 1.27 1.27)
					(thickness 0.15)
				)
				(justify left bottom)
				(hide yes)
			)
		)
		(property "Description" ""
			(at 262.89 109.22 0)
			(effects
				(font
					(size 1.27 1.27)
				)
				(hide yes)
			)
		)
		(property "Author" "Antmicro"
			(at 271.78 116.84 0)
			(effects
				(font
					(size 1.27 1.27)
					(thickness 0.15)
				)
				(justify left bottom)
				(hide yes)
			)
		)
		(property "License" "Apache-2.0"
			(at 271.78 119.38 0)
			(effects
				(font
					(size 1.27 1.27)
					(thickness 0.15)
				)
				(justify left bottom)
				(hide yes)
			)
		)
		(pin "1"
		)
		(instances
			(project "OCuLink to 10GbE adapter"
				(path ""
					(reference "#PWR0246")
					(unit 1)
				)
			)
			(project "thunderbolt-to-10gbe-adapter"
				(path ""
					(reference "#PWR0353")
					(unit 1)
				)
			)
		)
	)
	(symbol
		(lib_id "antmicroResistors0402:R_0R_0402")
		(at 162.56 97.79 0)
		(unit 1)
		(exclude_from_sim no)
		(in_bom yes)
		(on_board yes)
		(dnp no)
		(property "Reference" "R114"
			(at 159.512 96.52 0)
			(effects
				(font
					(size 1.27 1.27)
					(thickness 0.15)
				)
			)
		)
		(property "Value" "R_0R_0402"
			(at 182.88 110.49 0)
			(effects
				(font
					(size 1.27 1.27)
					(thickness 0.15)
				)
				(justify left bottom)
				(hide yes)
			)
		)
		(property "Footprint" "antmicro-footprints:R_0402_1005Metric"
			(at 182.88 113.03 0)
			(effects
				(font
					(size 1.27 1.27)
					(thickness 0.15)
				)
				(justify left bottom)
				(hide yes)
			)
		)
		(property "Datasheet" "https://industrial.panasonic.com/cdbs/www-data/pdf/RDA0000/AOA0000C301.pdf"
			(at 182.88 115.57 0)
			(effects
				(font
					(size 1.27 1.27)
					(thickness 0.15)
				)
				(justify left bottom)
				(hide yes)
			)
		)
		(property "Description" "SMD Chip Resistor, Jumper, 0 ohm, 100 mW, 0402 [1005 Metric], Thick Film, General Purpose"
			(at 182.88 130.81 0)
			(effects
				(font
					(size 1.27 1.27)
				)
				(justify left bottom)
				(hide yes)
			)
		)
		(property "MPN" "ERJ2GE0R00X"
			(at 182.88 118.11 0)
			(effects
				(font
					(size 1.27 1.27)
					(thickness 0.15)
				)
				(justify left bottom)
				(hide yes)
			)
		)
		(property "Manufacturer" "Panasonic"
			(at 182.88 120.65 0)
			(effects
				(font
					(size 1.27 1.27)
					(thickness 0.15)
				)
				(justify left bottom)
				(hide yes)
			)
		)
		(property "License" "Apache-2.0"
			(at 182.88 123.19 0)
			(effects
				(font
					(size 1.27 1.27)
					(thickness 0.15)
				)
				(justify left bottom)
				(hide yes)
			)
		)
		(property "Author" "Antmicro"
			(at 182.88 125.73 0)
			(effects
				(font
					(size 1.27 1.27)
					(thickness 0.15)
				)
				(justify left bottom)
				(hide yes)
			)
		)
		(property "Val" "0R"
			(at 168.91 96.52 0)
			(effects
				(font
					(size 1.27 1.27)
					(thickness 0.15)
				)
			)
		)
		(property "Tolerance" "~"
			(at 182.88 107.95 0)
			(effects
				(font
					(size 1.27 1.27)
				)
				(justify left bottom)
				(hide yes)
			)
		)
		(property "Current" "1A"
			(at 182.88 128.27 0)
			(effects
				(font
					(size 1.27 1.27)
					(thickness 0.15)
				)
				(justify left bottom)
				(hide yes)
			)
		)
		(pin "2"
		)
		(pin "1"
		)
		(instances
			(project "oculink-to-10gbe-adapter"
				(path ""
					(reference "R101")
					(unit 1)
				)
			)
			(project "thunderbolt-to-10gbe-adapter"
				(path ""
					(reference "R114")
					(unit 1)
				)
			)
		)
	)
	(symbol
		(lib_id "antmicroResistors0402:R_8k2_0402")
		(at 262.89 106.68 90)
		(unit 1)
		(exclude_from_sim no)
		(in_bom yes)
		(on_board yes)
		(dnp no)
		(property "Reference" "R119"
			(at 264.414 102.87 90)
			(effects
				(font
					(size 1.27 1.27)
					(thickness 0.15)
				)
				(justify right)
			)
		)
		(property "Value" "R_8k2_0402"
			(at 275.59 86.36 0)
			(effects
				(font
					(size 1.27 1.27)
					(thickness 0.15)
				)
				(justify left bottom)
				(hide yes)
			)
		)
		(property "Footprint" "antmicro-footprints:R_0402_1005Metric"
			(at 278.13 86.36 0)
			(effects
				(font
					(size 1.27 1.27)
					(thickness 0.15)
				)
				(justify left bottom)
				(hide yes)
			)
		)
		(property "Datasheet" "https://www.bourns.com/docs/product-datasheets/cr.pdf"
			(at 280.67 86.36 0)
			(effects
				(font
					(size 1.27 1.27)
					(thickness 0.15)
				)
				(justify left bottom)
				(hide yes)
			)
		)
		(property "Description" "SMD Chip Resistor"
			(at 262.89 106.68 0)
			(effects
				(font
					(size 1.27 1.27)
				)
				(hide yes)
			)
		)
		(property "MPN" "CR0402-FX-8201GLF"
			(at 283.21 86.36 0)
			(effects
				(font
					(size 1.27 1.27)
					(thickness 0.15)
				)
				(justify left bottom)
				(hide yes)
			)
		)
		(property "Manufacturer" "Bourns"
			(at 285.75 86.36 0)
			(effects
				(font
					(size 1.27 1.27)
					(thickness 0.15)
				)
				(justify left bottom)
				(hide yes)
			)
		)
		(property "License" "Apache-2.0"
			(at 288.29 86.36 0)
			(effects
				(font
					(size 1.27 1.27)
					(thickness 0.15)
				)
				(justify left bottom)
				(hide yes)
			)
		)
		(property "Author" "Antmicro"
			(at 290.83 86.36 0)
			(effects
				(font
					(size 1.27 1.27)
					(thickness 0.15)
				)
				(justify left bottom)
				(hide yes)
			)
		)
		(property "Val" "8k2"
			(at 264.414 105.41 90)
			(effects
				(font
					(size 1.27 1.27)
					(thickness 0.15)
				)
				(justify right)
			)
		)
		(property "Tolerance" "1%"
			(at 273.05 86.36 0)
			(effects
				(font
					(size 1.27 1.27)
				)
				(justify left bottom)
				(hide yes)
			)
		)
		(pin "1"
		)
		(pin "2"
		)
		(instances
			(project ""
				(path ""
					(reference "R54")
					(unit 1)
				)
			)
			(project "thunderbolt-to-10gbe-adapter"
				(path ""
					(reference "R119")
					(unit 1)
				)
			)
		)
	)
	(symbol
		(lib_id "antmicroCapacitors0402:C_220n_16V_0402")
		(at 160.02 120.65 0)
		(unit 1)
		(exclude_from_sim no)
		(in_bom yes)
		(on_board yes)
		(dnp no)
		(property "Reference" "C267"
			(at 161.29 119.38 0)
			(effects
				(font
					(size 1.27 1.27)
					(thickness 0.15)
				)
				(justify right)
			)
		)
		(property "Value" "C_220n_16V_0402"
			(at 180.34 130.81 0)
			(effects
				(font
					(size 1.27 1.27)
					(thickness 0.15)
				)
				(justify left bottom)
				(hide yes)
			)
		)
		(property "Footprint" "antmicro-footprints:C_0402_1005Metric"
			(at 180.34 133.35 0)
			(effects
				(font
					(size 1.27 1.27)
					(thickness 0.15)
				)
				(justify left bottom)
				(hide yes)
			)
		)
		(property "Datasheet" "https://www.murata.com/products/productdetail?partno=GRM155R71C224KA12%23"
			(at 180.34 135.89 0)
			(effects
				(font
					(size 1.27 1.27)
					(thickness 0.15)
				)
				(justify left bottom)
				(hide yes)
			)
		)
		(property "Description" "SMD Multilayer Ceramic Capacitor, 0.22 µF, 16 V, 0402 [1005 Metric], ± 10%, X7R, GRM Series"
			(at 160.02 120.65 0)
			(effects
				(font
					(size 1.27 1.27)
				)
				(hide yes)
			)
		)
		(property "MPN" "GRM155R71C224KA12D"
			(at 180.34 138.43 0)
			(effects
				(font
					(size 1.27 1.27)
					(thickness 0.15)
				)
				(justify left bottom)
				(hide yes)
			)
		)
		(property "Manufacturer" "Murata"
			(at 180.34 140.97 0)
			(effects
				(font
					(size 1.27 1.27)
					(thickness 0.15)
				)
				(justify left bottom)
				(hide yes)
			)
		)
		(property "License" "Apache-2.0"
			(at 180.34 143.51 0)
			(effects
				(font
					(size 1.27 1.27)
					(thickness 0.15)
				)
				(justify left bottom)
				(hide yes)
			)
		)
		(property "Author" "Antmicro"
			(at 180.34 146.05 0)
			(effects
				(font
					(size 1.27 1.27)
					(thickness 0.15)
				)
				(justify left bottom)
				(hide yes)
			)
		)
		(property "Val" "220n"
			(at 163.83 119.38 0)
			(effects
				(font
					(size 1.27 1.27)
					(thickness 0.15)
				)
				(justify left)
			)
		)
		(property "Voltage" "16V"
			(at 180.34 148.59 0)
			(effects
				(font
					(size 1.27 1.27)
				)
				(justify left bottom)
				(hide yes)
			)
		)
		(property "Dielectric" "X7R"
			(at 180.34 151.13 0)
			(effects
				(font
					(size 1.27 1.27)
				)
				(justify left bottom)
				(hide yes)
			)
		)
		(pin "2"
		)
		(pin "1"
		)
		(instances
			(project "OCuLink to 10GbE adapter"
				(path ""
					(reference "C193")
					(unit 1)
				)
			)
			(project "thunderbolt-to-10gbe-adapter"
				(path ""
					(reference "C267")
					(unit 1)
				)
			)
		)
	)
	(symbol
		(lib_id "antmicroCapacitors0402:C_220n_16V_0402")
		(at 168.91 102.87 0)
		(unit 1)
		(exclude_from_sim no)
		(in_bom yes)
		(on_board yes)
		(dnp no)
		(property "Reference" "C270"
			(at 170.18 101.6 0)
			(effects
				(font
					(size 1.27 1.27)
					(thickness 0.15)
				)
				(justify right)
			)
		)
		(property "Value" "C_220n_16V_0402"
			(at 189.23 113.03 0)
			(effects
				(font
					(size 1.27 1.27)
					(thickness 0.15)
				)
				(justify left bottom)
				(hide yes)
			)
		)
		(property "Footprint" "antmicro-footprints:C_0402_1005Metric"
			(at 189.23 115.57 0)
			(effects
				(font
					(size 1.27 1.27)
					(thickness 0.15)
				)
				(justify left bottom)
				(hide yes)
			)
		)
		(property "Datasheet" "https://www.murata.com/products/productdetail?partno=GRM155R71C224KA12%23"
			(at 189.23 118.11 0)
			(effects
				(font
					(size 1.27 1.27)
					(thickness 0.15)
				)
				(justify left bottom)
				(hide yes)
			)
		)
		(property "Description" "SMD Multilayer Ceramic Capacitor, 0.22 µF, 16 V, 0402 [1005 Metric], ± 10%, X7R, GRM Series"
			(at 168.91 102.87 0)
			(effects
				(font
					(size 1.27 1.27)
				)
				(hide yes)
			)
		)
		(property "MPN" "GRM155R71C224KA12D"
			(at 189.23 120.65 0)
			(effects
				(font
					(size 1.27 1.27)
					(thickness 0.15)
				)
				(justify left bottom)
				(hide yes)
			)
		)
		(property "Manufacturer" "Murata"
			(at 189.23 123.19 0)
			(effects
				(font
					(size 1.27 1.27)
					(thickness 0.15)
				)
				(justify left bottom)
				(hide yes)
			)
		)
		(property "License" "Apache-2.0"
			(at 189.23 125.73 0)
			(effects
				(font
					(size 1.27 1.27)
					(thickness 0.15)
				)
				(justify left bottom)
				(hide yes)
			)
		)
		(property "Author" "Antmicro"
			(at 189.23 128.27 0)
			(effects
				(font
					(size 1.27 1.27)
					(thickness 0.15)
				)
				(justify left bottom)
				(hide yes)
			)
		)
		(property "Val" "220n"
			(at 172.72 101.6 0)
			(effects
				(font
					(size 1.27 1.27)
					(thickness 0.15)
				)
				(justify left)
			)
		)
		(property "Voltage" "16V"
			(at 189.23 130.81 0)
			(effects
				(font
					(size 1.27 1.27)
				)
				(justify left bottom)
				(hide yes)
			)
		)
		(property "Dielectric" "X7R"
			(at 189.23 133.35 0)
			(effects
				(font
					(size 1.27 1.27)
				)
				(justify left bottom)
				(hide yes)
			)
		)
		(pin "2"
		)
		(pin "1"
		)
		(instances
			(project "OCuLink to 10GbE adapter"
				(path ""
					(reference "C190")
					(unit 1)
				)
			)
			(project "thunderbolt-to-10gbe-adapter"
				(path ""
					(reference "C270")
					(unit 1)
				)
			)
		)
	)
	(symbol
		(lib_id "antmicroResistors0402:R_3k3_0402")
		(at 236.22 82.55 90)
		(unit 1)
		(exclude_from_sim no)
		(in_bom yes)
		(on_board yes)
		(dnp no)
		(property "Reference" "R115"
			(at 237.744 78.74 90)
			(effects
				(font
					(size 1.27 1.27)
					(thickness 0.15)
				)
				(justify right)
			)
		)
		(property "Value" "R_3k3_0402"
			(at 248.92 62.23 0)
			(effects
				(font
					(size 1.27 1.27)
					(thickness 0.15)
				)
				(justify left bottom)
				(hide yes)
			)
		)
		(property "Footprint" "antmicro-footprints:R_0402_1005Metric"
			(at 251.46 62.23 0)
			(effects
				(font
					(size 1.27 1.27)
					(thickness 0.15)
				)
				(justify left bottom)
				(hide yes)
			)
		)
		(property "Datasheet" "https://www.bourns.com/docs/product-datasheets/cr.pdf"
			(at 254 62.23 0)
			(effects
				(font
					(size 1.27 1.27)
					(thickness 0.15)
				)
				(justify left bottom)
				(hide yes)
			)
		)
		(property "Description" "SMD Chip Resistor, 3.3 kohm, ± 1%, 63 mW, 0402 [1005 Metric], Thick Film, General Purpose"
			(at 236.22 82.55 0)
			(effects
				(font
					(size 1.27 1.27)
				)
				(hide yes)
			)
		)
		(property "MPN" "CR0402-FX-3301GLF"
			(at 256.54 62.23 0)
			(effects
				(font
					(size 1.27 1.27)
					(thickness 0.15)
				)
				(justify left bottom)
				(hide yes)
			)
		)
		(property "Manufacturer" "Bourns"
			(at 259.08 62.23 0)
			(effects
				(font
					(size 1.27 1.27)
					(thickness 0.15)
				)
				(justify left bottom)
				(hide yes)
			)
		)
		(property "License" "Apache-2.0"
			(at 261.62 62.23 0)
			(effects
				(font
					(size 1.27 1.27)
					(thickness 0.15)
				)
				(justify left bottom)
				(hide yes)
			)
		)
		(property "Author" "Antmicro"
			(at 264.16 62.23 0)
			(effects
				(font
					(size 1.27 1.27)
					(thickness 0.15)
				)
				(justify left bottom)
				(hide yes)
			)
		)
		(property "Val" "3k3"
			(at 237.744 81.28 90)
			(effects
				(font
					(size 1.27 1.27)
					(thickness 0.15)
				)
				(justify right)
			)
		)
		(property "Tolerance" "1%"
			(at 246.38 62.23 0)
			(effects
				(font
					(size 1.27 1.27)
				)
				(justify left bottom)
				(hide yes)
			)
		)
		(pin "1"
		)
		(pin "2"
		)
		(instances
			(project ""
				(path ""
					(reference "R51")
					(unit 1)
				)
			)
			(project "thunderbolt-to-10gbe-adapter"
				(path ""
					(reference "R115")
					(unit 1)
				)
			)
		)
	)
	(symbol
		(lib_id "antmicroTestPoints:Tag-Connect_TC2050-IDC-NL_2x5_P1.27mm")
		(at 274.32 139.7 0)
		(unit 1)
		(exclude_from_sim no)
		(in_bom no)
		(on_board yes)
		(dnp yes)
		(fields_autoplaced yes)
		(property "Reference" "J2"
			(at 290.195 132.08 0)
			(effects
				(font
					(size 1.27 1.27)
					(thickness 0.15)
				)
			)
		)
		(property "Value" "Tag-Connect_TC2050-IDC-NL_2x5_P1.27mm"
			(at 313.69 143.51 0)
			(effects
				(font
					(size 1.27 1.27)
					(thickness 0.15)
				)
				(justify left bottom)
				(hide yes)
			)
		)
		(property "Footprint" "antmicro-footprints:Tag-Connect_TC2050-IDC-NL_2x5_P1.27mm"
			(at 313.69 146.05 0)
			(effects
				(font
					(size 1.27 1.27)
					(thickness 0.15)
				)
				(justify left bottom)
				(hide yes)
			)
		)
		(property "Datasheet" "https://www.tag-connect.com/wp-content/uploads/bsk-pdf-manager/TC2050-IDC-NL_Datasheet_8.pdf"
			(at 313.69 148.59 0)
			(effects
				(font
					(size 1.27 1.27)
					(thickness 0.15)
				)
				(justify left bottom)
				(hide yes)
			)
		)
		(property "Description" "Tag Connect 2x5 1.27mm terminal"
			(at 313.69 161.29 0)
			(effects
				(font
					(size 1.27 1.27)
				)
				(justify left bottom)
				(hide yes)
			)
		)
		(property "MPN" "TC2050-IDC-NL"
			(at 290.195 134.62 0)
			(effects
				(font
					(size 1.27 1.27)
					(thickness 0.15)
				)
			)
		)
		(property "Manufacturer" "Tag Connect"
			(at 313.69 153.67 0)
			(effects
				(font
					(size 1.27 1.27)
					(thickness 0.15)
				)
				(justify left bottom)
				(hide yes)
			)
		)
		(property "Author" "Antmicro"
			(at 313.69 156.21 0)
			(effects
				(font
					(size 1.27 1.27)
					(thickness 0.15)
				)
				(justify left bottom)
				(hide yes)
			)
		)
		(property "License" "Apache-2.0"
			(at 313.69 158.75 0)
			(effects
				(font
					(size 1.27 1.27)
					(thickness 0.15)
				)
				(justify left bottom)
				(hide yes)
			)
		)
		(pin "3"
			(alternate "GND")
		)
		(pin "5"
			(alternate "GND")
		)
		(pin "8"
			(alternate "JTAG_TDI")
		)
		(pin "7"
			(alternate "NC")
		)
		(pin "6"
			(alternate "JTAG_TDO")
		)
		(pin "10"
			(alternate "JTAG_~{RESET}")
		)
		(pin "4"
			(alternate "JTAG_TCK")
		)
		(pin "2"
			(alternate "JTAG_TMS")
		)
		(pin "9"
			(alternate "GND")
		)
		(pin "1"
			(alternate "3V3")
		)
		(instances
			(project ""
				(path ""
					(reference "J7")
					(unit 1)
				)
			)
			(project "thunderbolt-to-10gbe-adapter"
				(path ""
					(reference "J2")
					(unit 1)
				)
			)
		)
	)
	(symbol
		(lib_id "antmicroCapacitors0402:C_220n_16V_0402")
		(at 168.91 118.11 0)
		(unit 1)
		(exclude_from_sim no)
		(in_bom yes)
		(on_board yes)
		(dnp no)
		(property "Reference" "C271"
			(at 170.18 116.84 0)
			(effects
				(font
					(size 1.27 1.27)
					(thickness 0.15)
				)
				(justify right)
			)
		)
		(property "Value" "C_220n_16V_0402"
			(at 189.23 128.27 0)
			(effects
				(font
					(size 1.27 1.27)
					(thickness 0.15)
				)
				(justify left bottom)
				(hide yes)
			)
		)
		(property "Footprint" "antmicro-footprints:C_0402_1005Metric"
			(at 189.23 130.81 0)
			(effects
				(font
					(size 1.27 1.27)
					(thickness 0.15)
				)
				(justify left bottom)
				(hide yes)
			)
		)
		(property "Datasheet" "https://www.murata.com/products/productdetail?partno=GRM155R71C224KA12%23"
			(at 189.23 133.35 0)
			(effects
				(font
					(size 1.27 1.27)
					(thickness 0.15)
				)
				(justify left bottom)
				(hide yes)
			)
		)
		(property "Description" "SMD Multilayer Ceramic Capacitor, 0.22 µF, 16 V, 0402 [1005 Metric], ± 10%, X7R, GRM Series"
			(at 168.91 118.11 0)
			(effects
				(font
					(size 1.27 1.27)
				)
				(hide yes)
			)
		)
		(property "MPN" "GRM155R71C224KA12D"
			(at 189.23 135.89 0)
			(effects
				(font
					(size 1.27 1.27)
					(thickness 0.15)
				)
				(justify left bottom)
				(hide yes)
			)
		)
		(property "Manufacturer" "Murata"
			(at 189.23 138.43 0)
			(effects
				(font
					(size 1.27 1.27)
					(thickness 0.15)
				)
				(justify left bottom)
				(hide yes)
			)
		)
		(property "License" "Apache-2.0"
			(at 189.23 140.97 0)
			(effects
				(font
					(size 1.27 1.27)
					(thickness 0.15)
				)
				(justify left bottom)
				(hide yes)
			)
		)
		(property "Author" "Antmicro"
			(at 189.23 143.51 0)
			(effects
				(font
					(size 1.27 1.27)
					(thickness 0.15)
				)
				(justify left bottom)
				(hide yes)
			)
		)
		(property "Val" "220n"
			(at 172.72 116.84 0)
			(effects
				(font
					(size 1.27 1.27)
					(thickness 0.15)
				)
				(justify left)
			)
		)
		(property "Voltage" "16V"
			(at 189.23 146.05 0)
			(effects
				(font
					(size 1.27 1.27)
				)
				(justify left bottom)
				(hide yes)
			)
		)
		(property "Dielectric" "X7R"
			(at 189.23 148.59 0)
			(effects
				(font
					(size 1.27 1.27)
				)
				(justify left bottom)
				(hide yes)
			)
		)
		(pin "2"
		)
		(pin "1"
		)
		(instances
			(project "OCuLink to 10GbE adapter"
				(path ""
					(reference "C192")
					(unit 1)
				)
			)
			(project "thunderbolt-to-10gbe-adapter"
				(path ""
					(reference "C271")
					(unit 1)
				)
			)
		)
	)
	(symbol
		(lib_id "antmicropower:GND")
		(at 271.78 109.22 0)
		(unit 1)
		(exclude_from_sim no)
		(in_bom yes)
		(on_board yes)
		(dnp no)
		(property "Reference" "#PWR0354"
			(at 280.67 111.76 0)
			(effects
				(font
					(size 1.27 1.27)
					(thickness 0.15)
				)
				(justify left bottom)
				(hide yes)
			)
		)
		(property "Value" "GND"
			(at 271.78 113.03 0)
			(effects
				(font
					(size 1.27 1.27)
					(thickness 0.15)
				)
			)
		)
		(property "Footprint" ""
			(at 280.67 116.84 0)
			(effects
				(font
					(size 1.27 1.27)
					(thickness 0.15)
				)
				(justify left bottom)
				(hide yes)
			)
		)
		(property "Datasheet" ""
			(at 280.67 121.92 0)
			(effects
				(font
					(size 1.27 1.27)
					(thickness 0.15)
				)
				(justify left bottom)
				(hide yes)
			)
		)
		(property "Description" ""
			(at 271.78 109.22 0)
			(effects
				(font
					(size 1.27 1.27)
				)
				(hide yes)
			)
		)
		(property "Author" "Antmicro"
			(at 280.67 116.84 0)
			(effects
				(font
					(size 1.27 1.27)
					(thickness 0.15)
				)
				(justify left bottom)
				(hide yes)
			)
		)
		(property "License" "Apache-2.0"
			(at 280.67 119.38 0)
			(effects
				(font
					(size 1.27 1.27)
					(thickness 0.15)
				)
				(justify left bottom)
				(hide yes)
			)
		)
		(pin "1"
		)
		(instances
			(project "OCuLink to 10GbE adapter"
				(path ""
					(reference "#PWR0247")
					(unit 1)
				)
			)
			(project "thunderbolt-to-10gbe-adapter"
				(path ""
					(reference "#PWR0354")
					(unit 1)
				)
			)
		)
	)
	(symbol
		(lib_id "antmicropower:GND")
		(at 271.78 152.4 0)
		(unit 1)
		(exclude_from_sim no)
		(in_bom yes)
		(on_board yes)
		(dnp no)
		(property "Reference" "#PWR0355"
			(at 280.67 154.94 0)
			(effects
				(font
					(size 1.27 1.27)
					(thickness 0.15)
				)
				(justify left bottom)
				(hide yes)
			)
		)
		(property "Value" "GND"
			(at 271.78 156.21 0)
			(effects
				(font
					(size 1.27 1.27)
					(thickness 0.15)
				)
			)
		)
		(property "Footprint" ""
			(at 280.67 160.02 0)
			(effects
				(font
					(size 1.27 1.27)
					(thickness 0.15)
				)
				(justify left bottom)
				(hide yes)
			)
		)
		(property "Datasheet" ""
			(at 280.67 165.1 0)
			(effects
				(font
					(size 1.27 1.27)
					(thickness 0.15)
				)
				(justify left bottom)
				(hide yes)
			)
		)
		(property "Description" ""
			(at 271.78 152.4 0)
			(effects
				(font
					(size 1.27 1.27)
				)
				(hide yes)
			)
		)
		(property "Author" "Antmicro"
			(at 280.67 160.02 0)
			(effects
				(font
					(size 1.27 1.27)
					(thickness 0.15)
				)
				(justify left bottom)
				(hide yes)
			)
		)
		(property "License" "Apache-2.0"
			(at 280.67 162.56 0)
			(effects
				(font
					(size 1.27 1.27)
					(thickness 0.15)
				)
				(justify left bottom)
				(hide yes)
			)
		)
		(pin "1"
		)
		(instances
			(project "OCuLink to 10GbE adapter"
				(path ""
					(reference "#PWR0248")
					(unit 1)
				)
			)
			(project "thunderbolt-to-10gbe-adapter"
				(path ""
					(reference "#PWR0355")
					(unit 1)
				)
			)
		)
	)
	(symbol
		(lib_id "antmicropower:GND")
		(at 308.61 152.4 0)
		(unit 1)
		(exclude_from_sim no)
		(in_bom yes)
		(on_board yes)
		(dnp no)
		(property "Reference" "#PWR0356"
			(at 317.5 154.94 0)
			(effects
				(font
					(size 1.27 1.27)
					(thickness 0.15)
				)
				(justify left bottom)
				(hide yes)
			)
		)
		(property "Value" "GND"
			(at 308.61 156.21 0)
			(effects
				(font
					(size 1.27 1.27)
					(thickness 0.15)
				)
			)
		)
		(property "Footprint" ""
			(at 317.5 160.02 0)
			(effects
				(font
					(size 1.27 1.27)
					(thickness 0.15)
				)
				(justify left bottom)
				(hide yes)
			)
		)
		(property "Datasheet" ""
			(at 317.5 165.1 0)
			(effects
				(font
					(size 1.27 1.27)
					(thickness 0.15)
				)
				(justify left bottom)
				(hide yes)
			)
		)
		(property "Description" ""
			(at 308.61 152.4 0)
			(effects
				(font
					(size 1.27 1.27)
				)
				(hide yes)
			)
		)
		(property "Author" "Antmicro"
			(at 317.5 160.02 0)
			(effects
				(font
					(size 1.27 1.27)
					(thickness 0.15)
				)
				(justify left bottom)
				(hide yes)
			)
		)
		(property "License" "Apache-2.0"
			(at 317.5 162.56 0)
			(effects
				(font
					(size 1.27 1.27)
					(thickness 0.15)
				)
				(justify left bottom)
				(hide yes)
			)
		)
		(pin "1"
		)
		(instances
			(project "OCuLink to 10GbE adapter"
				(path ""
					(reference "#PWR0249")
					(unit 1)
				)
			)
			(project "thunderbolt-to-10gbe-adapter"
				(path ""
					(reference "#PWR0356")
					(unit 1)
				)
			)
		)
	)
	(symbol
		(lib_id "antmicroCapacitors0402:C_220n_16V_0402")
		(at 160.02 151.13 0)
		(unit 1)
		(exclude_from_sim no)
		(in_bom yes)
		(on_board yes)
		(dnp no)
		(property "Reference" "C269"
			(at 161.29 149.86 0)
			(effects
				(font
					(size 1.27 1.27)
					(thickness 0.15)
				)
				(justify right)
			)
		)
		(property "Value" "C_220n_16V_0402"
			(at 180.34 161.29 0)
			(effects
				(font
					(size 1.27 1.27)
					(thickness 0.15)
				)
				(justify left bottom)
				(hide yes)
			)
		)
		(property "Footprint" "antmicro-footprints:C_0402_1005Metric"
			(at 180.34 163.83 0)
			(effects
				(font
					(size 1.27 1.27)
					(thickness 0.15)
				)
				(justify left bottom)
				(hide yes)
			)
		)
		(property "Datasheet" "https://www.murata.com/products/productdetail?partno=GRM155R71C224KA12%23"
			(at 180.34 166.37 0)
			(effects
				(font
					(size 1.27 1.27)
					(thickness 0.15)
				)
				(justify left bottom)
				(hide yes)
			)
		)
		(property "Description" "SMD Multilayer Ceramic Capacitor, 0.22 µF, 16 V, 0402 [1005 Metric], ± 10%, X7R, GRM Series"
			(at 160.02 151.13 0)
			(effects
				(font
					(size 1.27 1.27)
				)
				(hide yes)
			)
		)
		(property "MPN" "GRM155R71C224KA12D"
			(at 180.34 168.91 0)
			(effects
				(font
					(size 1.27 1.27)
					(thickness 0.15)
				)
				(justify left bottom)
				(hide yes)
			)
		)
		(property "Manufacturer" "Murata"
			(at 180.34 171.45 0)
			(effects
				(font
					(size 1.27 1.27)
					(thickness 0.15)
				)
				(justify left bottom)
				(hide yes)
			)
		)
		(property "License" "Apache-2.0"
			(at 180.34 173.99 0)
			(effects
				(font
					(size 1.27 1.27)
					(thickness 0.15)
				)
				(justify left bottom)
				(hide yes)
			)
		)
		(property "Author" "Antmicro"
			(at 180.34 176.53 0)
			(effects
				(font
					(size 1.27 1.27)
					(thickness 0.15)
				)
				(justify left bottom)
				(hide yes)
			)
		)
		(property "Val" "220n"
			(at 163.83 149.86 0)
			(effects
				(font
					(size 1.27 1.27)
					(thickness 0.15)
				)
				(justify left)
			)
		)
		(property "Voltage" "16V"
			(at 180.34 179.07 0)
			(effects
				(font
					(size 1.27 1.27)
				)
				(justify left bottom)
				(hide yes)
			)
		)
		(property "Dielectric" "X7R"
			(at 180.34 181.61 0)
			(effects
				(font
					(size 1.27 1.27)
				)
				(justify left bottom)
				(hide yes)
			)
		)
		(pin "2"
		)
		(pin "1"
		)
		(instances
			(project "OCuLink to 10GbE adapter"
				(path ""
					(reference "C197")
					(unit 1)
				)
			)
			(project "thunderbolt-to-10gbe-adapter"
				(path ""
					(reference "C269")
					(unit 1)
				)
			)
		)
	)
	(symbol
		(lib_id "antmicroInterfaceControllers:EZX710AT2_S_LMR5")
		(at 198.12 87.63 0)
		(unit 1)
		(exclude_from_sim no)
		(in_bom yes)
		(on_board yes)
		(dnp no)
		(fields_autoplaced yes)
		(property "Reference" "U14"
			(at 215.9 80.01 0)
			(effects
				(font
					(size 1.27 1.27)
					(thickness 0.15)
				)
			)
		)
		(property "Value" "EZX710AT2_S_LMR5"
			(at 274.32 92.71 0)
			(effects
				(font
					(size 1.27 1.27)
					(thickness 0.15)
				)
				(justify left bottom)
				(hide yes)
			)
		)
		(property "Footprint" "antmicro-footprints:FCBGA-503_22x22mm_Layout21x24_P1mm"
			(at 274.32 95.25 0)
			(effects
				(font
					(size 1.27 1.27)
					(thickness 0.15)
				)
				(justify left bottom)
				(hide yes)
			)
		)
		(property "Datasheet" "https://www.google.com/url?sa=t&source=web&rct=j&opi=89978449&url=https://cdrdv2-public.intel.com/596333/596333_X710-TM4_Datasheet_v_2_4.pdf&ved=2ahUKEwiSuv20_sCOAxXVCRAIHdxGO_UQFnoECBEQAQ&usg=AOvVaw1CjGyrGWE8ZvOdw4VBsY6U"
			(at 274.32 97.79 0)
			(effects
				(font
					(size 1.27 1.27)
					(thickness 0.15)
				)
				(justify left bottom)
				(hide yes)
			)
		)
		(property "Description" "Ethernet ICs Intel Ethernet Controller 10 Gigabit X7"
			(at 274.32 100.33 0)
			(effects
				(font
					(size 1.27 1.27)
					(thickness 0.15)
				)
				(justify left bottom)
				(hide yes)
			)
		)
		(property "MPN" "EZX710AT2 S LMR5"
			(at 215.9 82.55 0)
			(effects
				(font
					(size 1.27 1.27)
					(thickness 0.15)
				)
			)
		)
		(property "Manufacturer" "Intel"
			(at 274.32 102.87 0)
			(effects
				(font
					(size 1.27 1.27)
					(thickness 0.15)
				)
				(justify left bottom)
				(hide yes)
			)
		)
		(property "Author" "Antmicro"
			(at 274.32 105.41 0)
			(effects
				(font
					(size 1.27 1.27)
					(thickness 0.15)
				)
				(justify left bottom)
				(hide yes)
			)
		)
		(property "License" "Apache-2.0"
			(at 274.32 107.95 0)
			(effects
				(font
					(size 1.27 1.27)
					(thickness 0.15)
				)
				(justify left bottom)
				(hide yes)
			)
		)
		(pin "A13"
		)
		(pin "AA27"
		)
		(pin "W5"
		)
		(pin "P28"
		)
		(pin "U37"
		)
		(pin "E7"
		)
		(pin "M30"
		)
		(pin "T22"
		)
		(pin "AD32"
		)
		(pin "F14"
		)
		(pin "U7"
		)
		(pin "AB6"
		)
		(pin "AD10"
		)
		(pin "P26"
		)
		(pin "M28"
		)
		(pin "W23"
		)
		(pin "J7"
		)
		(pin "B14"
		)
		(pin "L33"
		)
		(pin "G3"
		)
		(pin "D42"
		)
		(pin "D30"
		)
		(pin "J39"
		)
		(pin "K14"
		)
		(pin "G31"
		)
		(pin "C23"
		)
		(pin "C37"
		)
		(pin "V4"
		)
		(pin "D2"
		)
		(pin "A29"
		)
		(pin "AA41"
		)
		(pin "N31"
		)
		(pin "R39"
		)
		(pin "Y26"
		)
		(pin "T28"
		)
		(pin "K10"
		)
		(pin "K40"
		)
		(pin "L13"
		)
		(pin "C25"
		)
		(pin "N13"
		)
		(pin "W25"
		)
		(pin "G35"
		)
		(pin "W15"
		)
		(pin "W17"
		)
		(pin "G13"
		)
		(pin "J27"
		)
		(pin "AC27"
		)
		(pin "AC41"
		)
		(pin "J19"
		)
		(pin "J29"
		)
		(pin "H32"
		)
		(pin "H28"
		)
		(pin "C33"
		)
		(pin "W21"
		)
		(pin "N27"
		)
		(pin "N17"
		)
		(pin "C13"
		)
		(pin "P32"
		)
		(pin "D12"
		)
		(pin "L29"
		)
		(pin "U41"
		)
		(pin "Y6"
		)
		(pin "K16"
		)
		(pin "Y36"
		)
		(pin "P16"
		)
		(pin "C15"
		)
		(pin "R35"
		)
		(pin "L19"
		)
		(pin "H30"
		)
		(pin "J13"
		)
		(pin "P18"
		)
		(pin "R19"
		)
		(pin "N29"
		)
		(pin "P14"
		)
		(pin "R17"
		)
		(pin "C29"
		)
		(pin "N15"
		)
		(pin "K38"
		)
		(pin "C27"
		)
		(pin "A31"
		)
		(pin "Y40"
		)
		(pin "L39"
		)
		(pin "E29"
		)
		(pin "A21"
		)
		(pin "Y4"
		)
		(pin "W33"
		)
		(pin "P22"
		)
		(pin "A23"
		)
		(pin "P20"
		)
		(pin "T20"
		)
		(pin "J3"
		)
		(pin "Y8"
		)
		(pin "W19"
		)
		(pin "AA13"
		)
		(pin "H6"
		)
		(pin "K36"
		)
		(pin "A3"
		)
		(pin "C11"
		)
		(pin "L1"
		)
		(pin "F30"
		)
		(pin "M24"
		)
		(pin "B16"
		)
		(pin "AA21"
		)
		(pin "G15"
		)
		(pin "W41"
		)
		(pin "Y42"
		)
		(pin "B20"
		)
		(pin "U9"
		)
		(pin "U11"
		)
		(pin "L25"
		)
		(pin "U17"
		)
		(pin "L9"
		)
		(pin "U13"
		)
		(pin "U15"
		)
		(pin "G21"
		)
		(pin "D38"
		)
		(pin "U21"
		)
		(pin "L27"
		)
		(pin "F32"
		)
		(pin "R37"
		)
		(pin "B2"
		)
		(pin "T2"
		)
		(pin "E3"
		)
		(pin "B4"
		)
		(pin "Y2"
		)
		(pin "P38"
		)
		(pin "H36"
		)
		(pin "E21"
		)
		(pin "AD30"
		)
		(pin "A19"
		)
		(pin "AC9"
		)
		(pin "W3"
		)
		(pin "G19"
		)
		(pin "B40"
		)
		(pin "F40"
		)
		(pin "D28"
		)
		(pin "F28"
		)
		(pin "F36"
		)
		(pin "C5"
		)
		(pin "P12"
		)
		(pin "D40"
		)
		(pin "U1"
		)
		(pin "K22"
		)
		(pin "K20"
		)
		(pin "M10"
		)
		(pin "B22"
		)
		(pin "H16"
		)
		(pin "V16"
		)
		(pin "M16"
		)
		(pin "G41"
		)
		(pin "F26"
		)
		(pin "AC33"
		)
		(pin "V18"
		)
		(pin "W11"
		)
		(pin "M20"
		)
		(pin "P8"
		)
		(pin "M18"
		)
		(pin "U5"
		)
		(pin "T8"
		)
		(pin "V14"
		)
		(pin "T34"
		)
		(pin "H34"
		)
		(pin "F24"
		)
		(pin "C19"
		)
		(pin "K18"
		)
		(pin "H26"
		)
		(pin "M14"
		)
		(pin "V2"
		)
		(pin "R11"
		)
		(pin "V12"
		)
		(pin "C41"
		)
		(pin "D26"
		)
		(pin "P10"
		)
		(pin "F42"
		)
		(pin "F34"
		)
		(pin "B32"
		)
		(pin "D24"
		)
		(pin "E33"
		)
		(pin "D36"
		)
		(pin "C9"
		)
		(pin "C31"
		)
		(pin "C17"
		)
		(pin "L35"
		)
		(pin "R3"
		)
		(pin "K8"
		)
		(pin "R21"
		)
		(pin "E31"
		)
		(pin "M12"
		)
		(pin "W9"
		)
		(pin "U19"
		)
		(pin "R27"
		)
		(pin "A7"
		)
		(pin "R5"
		)
		(pin "L21"
		)
		(pin "T12"
		)
		(pin "AD12"
		)
		(pin "F16"
		)
		(pin "U35"
		)
		(pin "AC23"
		)
		(pin "H4"
		)
		(pin "AB14"
		)
		(pin "R29"
		)
		(pin "T16"
		)
		(pin "F6"
		)
		(pin "AC7"
		)
		(pin "T30"
		)
		(pin "R15"
		)
		(pin "Y34"
		)
		(pin "AD8"
		)
		(pin "W13"
		)
		(pin "H38"
		)
		(pin "V34"
		)
		(pin "AD42"
		)
		(pin "B28"
		)
		(pin "R13"
		)
		(pin "V10"
		)
		(pin "D20"
		)
		(pin "A17"
		)
		(pin "AD6"
		)
		(pin "M38"
		)
		(pin "T10"
		)
		(pin "M26"
		)
		(pin "U29"
		)
		(pin "F12"
		)
		(pin "AD38"
		)
		(pin "F38"
		)
		(pin "B8"
		)
		(pin "Y30"
		)
		(pin "H8"
		)
		(pin "C35"
		)
		(pin "AD28"
		)
		(pin "AD14"
		)
		(pin "W29"
		)
		(pin "W35"
		)
		(pin "H2"
		)
		(pin "D16"
		)
		(pin "M6"
		)
		(pin "V24"
		)
		(pin "AC19"
		)
		(pin "J35"
		)
		(pin "R23"
		)
		(pin "M8"
		)
		(pin "J37"
		)
		(pin "AB12"
		)
		(pin "AC1"
		)
		(pin "L23"
		)
		(pin "N9"
		)
		(pin "Y32"
		)
		(pin "J15"
		)
		(pin "G33"
		)
		(pin "A35"
		)
		(pin "T14"
		)
		(pin "G5"
		)
		(pin "U23"
		)
		(pin "W31"
		)
		(pin "AB8"
		)
		(pin "AA17"
		)
		(pin "A39"
		)
		(pin "AB4"
		)
		(pin "H40"
		)
		(pin "K12"
		)
		(pin "G37"
		)
		(pin "T6"
		)
		(pin "N23"
		)
		(pin "A33"
		)
		(pin "AD36"
		)
		(pin "W1"
		)
		(pin "V20"
		)
		(pin "E23"
		)
		(pin "V36"
		)
		(pin "Y38"
		)
		(pin "V42"
		)
		(pin "AC21"
		)
		(pin "C3"
		)
		(pin "AB18"
		)
		(pin "AA19"
		)
		(pin "R31"
		)
		(pin "F18"
		)
		(pin "B12"
		)
		(pin "N5"
		)
		(pin "B6"
		)
		(pin "Y28"
		)
		(pin "D8"
		)
		(pin "A37"
		)
		(pin "N21"
		)
		(pin "AA11"
		)
		(pin "T4"
		)
		(pin "N35"
		)
		(pin "A41"
		)
		(pin "B18"
		)
		(pin "AB26"
		)
		(pin "U3"
		)
		(pin "D32"
		)
		(pin "D14"
		)
		(pin "L31"
		)
		(pin "K2"
		)
		(pin "T36"
		)
		(pin "AB22"
		)
		(pin "T42"
		)
		(pin "T32"
		)
		(pin "AB28"
		)
		(pin "V26"
		)
		(pin "U31"
		)
		(pin "AB24"
		)
		(pin "R9"
		)
		(pin "A9"
		)
		(pin "AC11"
		)
		(pin "B30"
		)
		(pin "AC17"
		)
		(pin "T18"
		)
		(pin "A27"
		)
		(pin "AA25"
		)
		(pin "U27"
		)
		(pin "Y14"
		)
		(pin "AB38"
		)
		(pin "AA29"
		)
		(pin "C39"
		)
		(pin "T24"
		)
		(pin "L7"
		)
		(pin "J31"
		)
		(pin "P30"
		)
		(pin "E13"
		)
		(pin "G39"
		)
		(pin "AB42"
		)
		(pin "E25"
		)
		(pin "Y10"
		)
		(pin "T40"
		)
		(pin "V22"
		)
		(pin "E1"
		)
		(pin "K24"
		)
		(pin "J17"
		)
		(pin "Y20"
		)
		(pin "E39"
		)
		(pin "AC31"
		)
		(pin "AB32"
		)
		(pin "A5"
		)
		(pin "AB30"
		)
		(pin "L17"
		)
		(pin "F20"
		)
		(pin "N19"
		)
		(pin "N41"
		)
		(pin "U33"
		)
		(pin "E11"
		)
		(pin "J1"
		)
		(pin "H14"
		)
		(pin "G29"
		)
		(pin "E17"
		)
		(pin "K6"
		)
		(pin "D10"
		)
		(pin "P6"
		)
		(pin "K32"
		)
		(pin "AA15"
		)
		(pin "M32"
		)
		(pin "J25"
		)
		(pin "K34"
		)
		(pin "AA31"
		)
		(pin "B24"
		)
		(pin "A25"
		)
		(pin "G25"
		)
		(pin "N11"
		)
		(pin "E5"
		)
		(pin "AD22"
		)
		(pin "K42"
		)
		(pin "D6"
		)
		(pin "E27"
		)
		(pin "N7"
		)
		(pin "N3"
		)
		(pin "J21"
		)
		(pin "H20"
		)
		(pin "H12"
		)
		(pin "F4"
		)
		(pin "U25"
		)
		(pin "K4"
		)
		(pin "M22"
		)
		(pin "P24"
		)
		(pin "AA3"
		)
		(pin "E35"
		)
		(pin "AC13"
		)
		(pin "B38"
		)
		(pin "W37"
		)
		(pin "M34"
		)
		(pin "G1"
		)
		(pin "AD26"
		)
		(pin "N37"
		)
		(pin "E37"
		)
		(pin "W39"
		)
		(pin "AA35"
		)
		(pin "E19"
		)
		(pin "H42"
		)
		(pin "AC39"
		)
		(pin "AD2"
		)
		(pin "AA37"
		)
		(pin "H22"
		)
		(pin "B26"
		)
		(pin "A15"
		)
		(pin "K28"
		)
		(pin "AA39"
		)
		(pin "P40"
		)
		(pin "N39"
		)
		(pin "AA9"
		)
		(pin "K26"
		)
		(pin "B42"
		)
		(pin "Y12"
		)
		(pin "V8"
		)
		(pin "H10"
		)
		(pin "AD40"
		)
		(pin "J11"
		)
		(pin "V38"
		)
		(pin "V40"
		)
		(pin "F2"
		)
		(pin "P34"
		)
		(pin "AA23"
		)
		(pin "T26"
		)
		(pin "D4"
		)
		(pin "F22"
		)
		(pin "M42"
		)
		(pin "J9"
		)
		(pin "F8"
		)
		(pin "N1"
		)
		(pin "AD20"
		)
		(pin "V28"
		)
		(pin "AA5"
		)
		(pin "AC5"
		)
		(pin "AD4"
		)
		(pin "AB2"
		)
		(pin "AA1"
		)
		(pin "P2"
		)
		(pin "R1"
		)
		(pin "P42"
		)
		(pin "AC3"
		)
		(pin "G11"
		)
		(pin "N33"
		)
		(pin "U39"
		)
		(pin "J5"
		)
		(pin "R33"
		)
		(pin "W27"
		)
		(pin "W7"
		)
		(pin "L5"
		)
		(pin "R7"
		)
		(pin "L3"
		)
		(pin "B36"
		)
		(pin "P4"
		)
		(pin "AA7"
		)
		(pin "M2"
		)
		(pin "C1"
		)
		(pin "AC25"
		)
		(pin "AB40"
		)
		(pin "E15"
		)
		(pin "H24"
		)
		(pin "P36"
		)
		(pin "V6"
		)
		(pin "R25"
		)
		(pin "A11"
		)
		(pin "G23"
		)
		(pin "AD34"
		)
		(pin "Y24"
		)
		(pin "Y18"
		)
		(pin "V32"
		)
		(pin "J33"
		)
		(pin "L15"
		)
		(pin "C7"
		)
		(pin "J41"
		)
		(pin "AA33"
		)
		(pin "M4"
		)
		(pin "E9"
		)
		(pin "V30"
		)
		(pin "AC15"
		)
		(pin "AB16"
		)
		(pin "L41"
		)
		(pin "AC29"
		)
		(pin "N25"
		)
		(pin "F10"
		)
		(pin "Y16"
		)
		(pin "K30"
		)
		(pin "AD16"
		)
		(pin "AD18"
		)
		(pin "H18"
		)
		(pin "AB10"
		)
		(pin "G27"
		)
		(pin "M40"
		)
		(pin "B34"
		)
		(pin "B10"
		)
		(pin "L11"
		)
		(pin "J23"
		)
		(pin "AB36"
		)
		(pin "Y22"
		)
		(pin "AD24"
		)
		(pin "D34"
		)
		(pin "E41"
		)
		(pin "L37"
		)
		(pin "R41"
		)
		(pin "G7"
		)
		(pin "AB34"
		)
		(pin "T38"
		)
		(pin "AB20"
		)
		(pin "G17"
		)
		(pin "M36"
		)
		(pin "G9"
		)
		(pin "C21"
		)
		(pin "AC37"
		)
		(pin "AC35"
		)
		(pin "D18"
		)
		(pin "D22"
		)
		(instances
			(project "OCuLink to 10GbE adapter"
				(path ""
					(reference "U9")
					(unit 1)
				)
			)
			(project "thunderbolt-to-10gbe-adapter"
				(path ""
					(reference "U14")
					(unit 1)
				)
			)
		)
	)
)
